FILE_TYPE = MACRO_DRAWING;
SET COLOR_WIRE YELLOW;
SET COLOR_PROP MONO;
SET COLOR_DOT WHITE;
SET COLOR_ARC YELLOW;
SET COLOR_BODY GREEN;
SET COLOR_NOTE MONO;
SET PROP_DISPLAY VALUE;
SET PAGE_NUMBER P87;
FORCEADD OFFPAGE..3
(1600 5200);
FORCEPROP 2 LAST $XR0 62 
J 0
(1814 5200);
DISPLAY 0.638298 (1814 5200);
PAINT MONO (1814 5200);
FORCEPROP 2 LAST $XR1 88 
J 0
(1904 5200);
DISPLAY 0.638298 (1904 5200);
PAINT MONO (1904 5200);
FORCEPROP 2 LAST CDS_LIB mstr_standard
J 0
(1600 5200);
DISPLAY 0.787234 (1600 5200);
PAINT MONO (1600 5200);
DISPLAY INVISIBLE (1600 5200);
FORCEPROP 1 LAST OFFPAGE TRUE
J 0
(1925 5075);
DISPLAY 0.936170 (1925 5075);
PAINT GREEN (1925 5075);
DISPLAY INVISIBLE (1925 5075);
FORCEPROP 1 LAST COMMENT_BODY TRUE
J 0
(1550 5100);
DISPLAY 0.936170 (1550 5100);
PAINT GREEN (1550 5100);
DISPLAY INVISIBLE (1550 5100);
FORCEPROP 2 LAST PATH I1
J 0
(1800 5275);
DISPLAY 0.787234 (1800 5275);
PAINT MONO (1800 5275);
DISPLAY INVISIBLE (1800 5275);
FORCEADD TAP..6
R 2
(-1750 2200);
FORCEPROP 3 LASTPIN (-1800 2200) SIG_NAME M_M_DQ<8>
J 0
(-1790 2210);
DISPLAY 0.659574 (-1790 2210);
PAINT MONO (-1790 2210);
DISPLAY INVISIBLE (-1790 2210);
FORCEPROP 1 LASTPIN (-1800 2200) BN 8
J 2
(-1750 2210);
DISPLAY 0.617021 (-1750 2210);
PAINT PINK (-1750 2210);
FORCEPROP 2 LAST CDS_LIB mstr_standard
J 2
(-1750 2200);
DISPLAY 0.787234 (-1750 2200);
PAINT MONO (-1750 2200);
DISPLAY INVISIBLE (-1750 2200);
FORCEPROP 1 LAST BODY_TYPE PLUMBING
J 2
(-1750 2150);
DISPLAY 1.234043 (-1750 2150);
PAINT GREEN (-1750 2150);
DISPLAY INVISIBLE (-1750 2150);
FORCEPROP 1 LAST HDL_TAP TRUE
J 2
(-2075 2075);
DISPLAY 1.234043 (-2075 2075);
PAINT GREEN (-2075 2075);
DISPLAY INVISIBLE (-2075 2075);
FORCEPROP 1 LAST PATH I100
J 2
(-1750 2200);
DISPLAY 0.936170 (-1750 2200);
PAINT GREEN (-1750 2200);
DISPLAY INVISIBLE (-1750 2200);
FORCEADD TAP..6
R 2
(-1750 2300);
FORCEPROP 3 LASTPIN (-1800 2300) SIG_NAME M_M_DQ<10>
J 0
(-1790 2310);
DISPLAY 0.659574 (-1790 2310);
PAINT MONO (-1790 2310);
DISPLAY INVISIBLE (-1790 2310);
FORCEPROP 1 LASTPIN (-1800 2300) BN 10
J 2
(-1750 2310);
DISPLAY 0.617021 (-1750 2310);
PAINT PINK (-1750 2310);
FORCEPROP 2 LAST CDS_LIB mstr_standard
J 2
(-1750 2300);
DISPLAY 0.787234 (-1750 2300);
PAINT MONO (-1750 2300);
DISPLAY INVISIBLE (-1750 2300);
FORCEPROP 1 LAST BODY_TYPE PLUMBING
J 2
(-1750 2250);
DISPLAY 1.234043 (-1750 2250);
PAINT GREEN (-1750 2250);
DISPLAY INVISIBLE (-1750 2250);
FORCEPROP 1 LAST HDL_TAP TRUE
J 2
(-2075 2175);
DISPLAY 1.234043 (-2075 2175);
PAINT GREEN (-2075 2175);
DISPLAY INVISIBLE (-2075 2175);
FORCEPROP 1 LAST PATH I101
J 2
(-1750 2300);
DISPLAY 0.936170 (-1750 2300);
PAINT GREEN (-1750 2300);
DISPLAY INVISIBLE (-1750 2300);
FORCEADD TAP..6
R 2
(-1750 2350);
FORCEPROP 3 LASTPIN (-1800 2350) SIG_NAME M_M_DQ<13>
J 0
(-1790 2360);
DISPLAY 0.659574 (-1790 2360);
PAINT MONO (-1790 2360);
DISPLAY INVISIBLE (-1790 2360);
FORCEPROP 1 LASTPIN (-1800 2350) BN 13
J 2
(-1750 2360);
DISPLAY 0.617021 (-1750 2360);
PAINT PINK (-1750 2360);
FORCEPROP 2 LAST CDS_LIB mstr_standard
J 2
(-1750 2350);
DISPLAY 0.787234 (-1750 2350);
PAINT MONO (-1750 2350);
DISPLAY INVISIBLE (-1750 2350);
FORCEPROP 1 LAST BODY_TYPE PLUMBING
J 2
(-1750 2300);
DISPLAY 1.234043 (-1750 2300);
PAINT GREEN (-1750 2300);
DISPLAY INVISIBLE (-1750 2300);
FORCEPROP 1 LAST HDL_TAP TRUE
J 2
(-2075 2225);
DISPLAY 1.234043 (-2075 2225);
PAINT GREEN (-2075 2225);
DISPLAY INVISIBLE (-2075 2225);
FORCEPROP 1 LAST PATH I102
J 2
(-1750 2350);
DISPLAY 0.936170 (-1750 2350);
PAINT GREEN (-1750 2350);
DISPLAY INVISIBLE (-1750 2350);
FORCEADD TAP..6
R 2
(-1750 2100);
FORCEPROP 3 LASTPIN (-1800 2100) SIG_NAME M_M_DQ<6>
J 0
(-1790 2110);
DISPLAY 0.659574 (-1790 2110);
PAINT MONO (-1790 2110);
DISPLAY INVISIBLE (-1790 2110);
FORCEPROP 1 LASTPIN (-1800 2100) BN 6
J 2
(-1750 2110);
DISPLAY 0.617021 (-1750 2110);
PAINT PINK (-1750 2110);
FORCEPROP 2 LAST CDS_LIB mstr_standard
J 2
(-1750 2100);
DISPLAY 0.787234 (-1750 2100);
PAINT MONO (-1750 2100);
DISPLAY INVISIBLE (-1750 2100);
FORCEPROP 1 LAST BODY_TYPE PLUMBING
J 2
(-1750 2050);
DISPLAY 1.234043 (-1750 2050);
PAINT GREEN (-1750 2050);
DISPLAY INVISIBLE (-1750 2050);
FORCEPROP 1 LAST HDL_TAP TRUE
J 2
(-2075 1975);
DISPLAY 1.234043 (-2075 1975);
PAINT GREEN (-2075 1975);
DISPLAY INVISIBLE (-2075 1975);
FORCEPROP 1 LAST PATH I103
J 2
(-1750 2100);
DISPLAY 0.936170 (-1750 2100);
PAINT GREEN (-1750 2100);
DISPLAY INVISIBLE (-1750 2100);
FORCEADD TAP..6
R 2
(-1750 2050);
FORCEPROP 3 LASTPIN (-1800 2050) SIG_NAME M_M_DQ<7>
J 0
(-1790 2060);
DISPLAY 0.659574 (-1790 2060);
PAINT MONO (-1790 2060);
DISPLAY INVISIBLE (-1790 2060);
FORCEPROP 1 LASTPIN (-1800 2050) BN 7
J 2
(-1750 2060);
DISPLAY 0.617021 (-1750 2060);
PAINT PINK (-1750 2060);
FORCEPROP 2 LAST CDS_LIB mstr_standard
J 2
(-1750 2050);
DISPLAY 0.787234 (-1750 2050);
PAINT MONO (-1750 2050);
DISPLAY INVISIBLE (-1750 2050);
FORCEPROP 1 LAST BODY_TYPE PLUMBING
J 2
(-1750 2000);
DISPLAY 1.234043 (-1750 2000);
PAINT GREEN (-1750 2000);
DISPLAY INVISIBLE (-1750 2000);
FORCEPROP 1 LAST HDL_TAP TRUE
J 2
(-2075 1925);
DISPLAY 1.234043 (-2075 1925);
PAINT GREEN (-2075 1925);
DISPLAY INVISIBLE (-2075 1925);
FORCEPROP 1 LAST PATH I104
J 2
(-1750 2050);
DISPLAY 0.936170 (-1750 2050);
PAINT GREEN (-1750 2050);
DISPLAY INVISIBLE (-1750 2050);
FORCEADD TAP..6
R 2
(-1750 2000);
FORCEPROP 3 LASTPIN (-1800 2000) SIG_NAME M_M_DQ<4>
J 0
(-1790 2010);
DISPLAY 0.659574 (-1790 2010);
PAINT MONO (-1790 2010);
DISPLAY INVISIBLE (-1790 2010);
FORCEPROP 1 LASTPIN (-1800 2000) BN 4
J 2
(-1750 2010);
DISPLAY 0.617021 (-1750 2010);
PAINT PINK (-1750 2010);
FORCEPROP 2 LAST CDS_LIB mstr_standard
J 2
(-1750 2000);
DISPLAY 0.787234 (-1750 2000);
PAINT MONO (-1750 2000);
DISPLAY INVISIBLE (-1750 2000);
FORCEPROP 1 LAST BODY_TYPE PLUMBING
J 2
(-1750 1950);
DISPLAY 1.234043 (-1750 1950);
PAINT GREEN (-1750 1950);
DISPLAY INVISIBLE (-1750 1950);
FORCEPROP 1 LAST HDL_TAP TRUE
J 2
(-2075 1875);
DISPLAY 1.234043 (-2075 1875);
PAINT GREEN (-2075 1875);
DISPLAY INVISIBLE (-2075 1875);
FORCEPROP 1 LAST PATH I105
J 2
(-1750 2000);
DISPLAY 0.936170 (-1750 2000);
PAINT GREEN (-1750 2000);
DISPLAY INVISIBLE (-1750 2000);
FORCEADD TAP..6
R 2
(-1750 1950);
FORCEPROP 3 LASTPIN (-1800 1950) SIG_NAME M_M_DQ<5>
J 0
(-1790 1960);
DISPLAY 0.659574 (-1790 1960);
PAINT MONO (-1790 1960);
DISPLAY INVISIBLE (-1790 1960);
FORCEPROP 1 LASTPIN (-1800 1950) BN 5
J 2
(-1750 1960);
DISPLAY 0.617021 (-1750 1960);
PAINT PINK (-1750 1960);
FORCEPROP 2 LAST CDS_LIB mstr_standard
J 2
(-1750 1950);
DISPLAY 0.787234 (-1750 1950);
PAINT MONO (-1750 1950);
DISPLAY INVISIBLE (-1750 1950);
FORCEPROP 1 LAST BODY_TYPE PLUMBING
J 2
(-1750 1900);
DISPLAY 1.234043 (-1750 1900);
PAINT GREEN (-1750 1900);
DISPLAY INVISIBLE (-1750 1900);
FORCEPROP 1 LAST HDL_TAP TRUE
J 2
(-2075 1825);
DISPLAY 1.234043 (-2075 1825);
PAINT GREEN (-2075 1825);
DISPLAY INVISIBLE (-2075 1825);
FORCEPROP 1 LAST PATH I106
J 2
(-1750 1950);
DISPLAY 0.936170 (-1750 1950);
PAINT GREEN (-1750 1950);
DISPLAY INVISIBLE (-1750 1950);
FORCEADD TAP..6
R 2
(-1750 1900);
FORCEPROP 3 LASTPIN (-1800 1900) SIG_NAME M_M_DQ<2>
J 0
(-1790 1910);
DISPLAY 0.659574 (-1790 1910);
PAINT MONO (-1790 1910);
DISPLAY INVISIBLE (-1790 1910);
FORCEPROP 1 LASTPIN (-1800 1900) BN 2
J 2
(-1750 1910);
DISPLAY 0.617021 (-1750 1910);
PAINT PINK (-1750 1910);
FORCEPROP 2 LAST CDS_LIB mstr_standard
J 2
(-1750 1900);
DISPLAY 0.787234 (-1750 1900);
PAINT MONO (-1750 1900);
DISPLAY INVISIBLE (-1750 1900);
FORCEPROP 1 LAST BODY_TYPE PLUMBING
J 2
(-1750 1850);
DISPLAY 1.234043 (-1750 1850);
PAINT GREEN (-1750 1850);
DISPLAY INVISIBLE (-1750 1850);
FORCEPROP 1 LAST HDL_TAP TRUE
J 2
(-2075 1775);
DISPLAY 1.234043 (-2075 1775);
PAINT GREEN (-2075 1775);
DISPLAY INVISIBLE (-2075 1775);
FORCEPROP 1 LAST PATH I107
J 2
(-1750 1900);
DISPLAY 0.936170 (-1750 1900);
PAINT GREEN (-1750 1900);
DISPLAY INVISIBLE (-1750 1900);
FORCEADD TAP..6
R 2
(-1750 1750);
FORCEPROP 3 LASTPIN (-1800 1750) SIG_NAME M_M_DQ<1>
J 0
(-1790 1760);
DISPLAY 0.659574 (-1790 1760);
PAINT MONO (-1790 1760);
DISPLAY INVISIBLE (-1790 1760);
FORCEPROP 1 LASTPIN (-1800 1750) BN 1
J 2
(-1750 1760);
DISPLAY 0.617021 (-1750 1760);
PAINT PINK (-1750 1760);
FORCEPROP 2 LAST CDS_LIB mstr_standard
J 2
(-1750 1750);
DISPLAY 0.787234 (-1750 1750);
PAINT MONO (-1750 1750);
DISPLAY INVISIBLE (-1750 1750);
FORCEPROP 1 LAST BODY_TYPE PLUMBING
J 2
(-1750 1700);
DISPLAY 1.234043 (-1750 1700);
PAINT GREEN (-1750 1700);
DISPLAY INVISIBLE (-1750 1700);
FORCEPROP 1 LAST HDL_TAP TRUE
J 2
(-2075 1625);
DISPLAY 1.234043 (-2075 1625);
PAINT GREEN (-2075 1625);
DISPLAY INVISIBLE (-2075 1625);
FORCEPROP 1 LAST PATH I108
J 2
(-1750 1750);
DISPLAY 0.936170 (-1750 1750);
PAINT GREEN (-1750 1750);
DISPLAY INVISIBLE (-1750 1750);
FORCEADD TAP..6
R 2
(-1750 1850);
FORCEPROP 3 LASTPIN (-1800 1850) SIG_NAME M_M_DQ<3>
J 0
(-1790 1860);
DISPLAY 0.659574 (-1790 1860);
PAINT MONO (-1790 1860);
DISPLAY INVISIBLE (-1790 1860);
FORCEPROP 1 LASTPIN (-1800 1850) BN 3
J 2
(-1750 1860);
DISPLAY 0.617021 (-1750 1860);
PAINT PINK (-1750 1860);
FORCEPROP 2 LAST CDS_LIB mstr_standard
J 2
(-1750 1850);
DISPLAY 0.787234 (-1750 1850);
PAINT MONO (-1750 1850);
DISPLAY INVISIBLE (-1750 1850);
FORCEPROP 1 LAST BODY_TYPE PLUMBING
J 2
(-1750 1800);
DISPLAY 1.234043 (-1750 1800);
PAINT GREEN (-1750 1800);
DISPLAY INVISIBLE (-1750 1800);
FORCEPROP 1 LAST HDL_TAP TRUE
J 2
(-2075 1725);
DISPLAY 1.234043 (-2075 1725);
PAINT GREEN (-2075 1725);
DISPLAY INVISIBLE (-2075 1725);
FORCEPROP 1 LAST PATH I109
J 2
(-1750 1850);
DISPLAY 0.936170 (-1750 1850);
PAINT GREEN (-1750 1850);
DISPLAY INVISIBLE (-1750 1850);
FORCEADD PVDDQ_KLM..1
(-1450 2600);
FORCEPROP 3 LASTPIN (-1450 2550) SIG_NAME PVDDQ_KLM\g
J 0
(-1440 2560);
DISPLAY 0.659574 (-1440 2560);
PAINT MONO (-1440 2560);
DISPLAY INVISIBLE (-1440 2560);
FORCEPROP 1 LAST VOLTAGE 1.2V
J 0
(-1495 2557);
DISPLAY 0.340426 (-1495 2557);
PAINT SKYBLUE (-1495 2557);
DISPLAY INVISIBLE (-1495 2557);
FORCEPROP 2 LAST BOM_COST MEM
J 0
(-1450 2605);
PAINT ORANGE (-1450 2605);
DISPLAY INVISIBLE (-1450 2605);
FORCEPROP 2 LAST CDS_LIB mstr_symbols
J 0
(-1450 2600);
PAINT ORANGE (-1450 2600);
DISPLAY INVISIBLE (-1450 2600);
FORCEPROP 1 LAST BODY_TYPE PLUMBING
J 0
(-1495 2557);
DISPLAY 0.340426 (-1495 2557);
PAINT GREEN (-1495 2557);
DISPLAY INVISIBLE (-1495 2557);
FORCEPROP 1 LAST PATH I11
J 0
(-1400 2625);
DISPLAY 0.872340 (-1400 2625);
PAINT AQUA (-1400 2625);
DISPLAY INVISIBLE (-1400 2625);
FORCEPROP 2 LAST ROOM DDR4_CH_D
J 0
(-1450 2700);
DISPLAY 0.787234 (-1450 2700);
PAINT ORANGE (-1450 2700);
DISPLAY INVISIBLE (-1450 2700);
FORCEPROP 1 LAST HDL_POWER PVDDQ_KLM
J 1
(-1450 2650);
DISPLAY 0.872340 (-1450 2650);
PAINT GREEN (-1450 2650);
DISPLAY INVISIBLE (-1450 2650);
FORCEADD TAP..6
R 2
(-1750 1800);
FORCEPROP 3 LASTPIN (-1800 1800) SIG_NAME M_M_DQ<0>
J 0
(-1790 1810);
DISPLAY 0.659574 (-1790 1810);
PAINT MONO (-1790 1810);
DISPLAY INVISIBLE (-1790 1810);
FORCEPROP 1 LASTPIN (-1800 1800) BN 0
J 2
(-1750 1810);
DISPLAY 0.617021 (-1750 1810);
PAINT PINK (-1750 1810);
FORCEPROP 2 LAST CDS_LIB mstr_standard
J 2
(-1750 1800);
DISPLAY 0.787234 (-1750 1800);
PAINT MONO (-1750 1800);
DISPLAY INVISIBLE (-1750 1800);
FORCEPROP 1 LAST BODY_TYPE PLUMBING
J 2
(-1750 1750);
DISPLAY 1.234043 (-1750 1750);
PAINT GREEN (-1750 1750);
DISPLAY INVISIBLE (-1750 1750);
FORCEPROP 1 LAST HDL_TAP TRUE
J 2
(-2075 1675);
DISPLAY 1.234043 (-2075 1675);
PAINT GREEN (-2075 1675);
DISPLAY INVISIBLE (-2075 1675);
FORCEPROP 1 LAST PATH I110
J 2
(-1750 1800);
DISPLAY 0.936170 (-1750 1800);
PAINT GREEN (-1750 1800);
DISPLAY INVISIBLE (-1750 1800);
FORCEADD TAP..6
(-3250 4850);
FORCEPROP 3 LASTPIN (-3200 4850) SIG_NAME M_M_MA<16>
J 0
(-3190 4860);
DISPLAY 0.659574 (-3190 4860);
PAINT MONO (-3190 4860);
DISPLAY INVISIBLE (-3190 4860);
FORCEPROP 1 LASTPIN (-3200 4850) BN 16
J 0
(-3250 4860);
DISPLAY 0.617021 (-3250 4860);
PAINT PINK (-3250 4860);
FORCEPROP 2 LAST CDS_LIB mstr_standard
J 2
(-3250 4850);
DISPLAY 0.787234 (-3250 4850);
PAINT MONO (-3250 4850);
DISPLAY INVISIBLE (-3250 4850);
FORCEPROP 1 LAST BODY_TYPE PLUMBING
J 0
(-3250 4800);
DISPLAY 1.234043 (-3250 4800);
PAINT GREEN (-3250 4800);
DISPLAY INVISIBLE (-3250 4800);
FORCEPROP 1 LAST HDL_TAP TRUE
J 0
(-2925 4725);
DISPLAY 1.234043 (-2925 4725);
PAINT GREEN (-2925 4725);
DISPLAY INVISIBLE (-2925 4725);
FORCEPROP 1 LAST PATH I112
J 0
(-3250 4850);
DISPLAY 0.936170 (-3250 4850);
PAINT GREEN (-3250 4850);
DISPLAY INVISIBLE (-3250 4850);
FORCEADD TAP..6
(-3250 4900);
FORCEPROP 3 LASTPIN (-3200 4900) SIG_NAME M_M_MA<17>
J 0
(-3190 4910);
DISPLAY 0.659574 (-3190 4910);
PAINT MONO (-3190 4910);
DISPLAY INVISIBLE (-3190 4910);
FORCEPROP 1 LASTPIN (-3200 4900) BN 17
J 0
(-3250 4910);
DISPLAY 0.617021 (-3250 4910);
PAINT PINK (-3250 4910);
FORCEPROP 2 LAST CDS_LIB mstr_standard
J 0
(-3250 4900);
DISPLAY 0.787234 (-3250 4900);
PAINT MONO (-3250 4900);
DISPLAY INVISIBLE (-3250 4900);
FORCEPROP 1 LAST BODY_TYPE PLUMBING
J 0
(-3250 4850);
DISPLAY 1.234043 (-3250 4850);
PAINT GREEN (-3250 4850);
DISPLAY INVISIBLE (-3250 4850);
FORCEPROP 1 LAST HDL_TAP TRUE
J 0
(-2925 4775);
DISPLAY 1.234043 (-2925 4775);
PAINT GREEN (-2925 4775);
DISPLAY INVISIBLE (-2925 4775);
FORCEPROP 1 LAST PATH I113
J 0
(-3250 4900);
DISPLAY 0.936170 (-3250 4900);
PAINT GREEN (-3250 4900);
DISPLAY INVISIBLE (-3250 4900);
FORCEADD TAP..6
(-3250 4800);
FORCEPROP 3 LASTPIN (-3200 4800) SIG_NAME M_M_MA<15>
J 0
(-3190 4810);
DISPLAY 0.659574 (-3190 4810);
PAINT MONO (-3190 4810);
DISPLAY INVISIBLE (-3190 4810);
FORCEPROP 1 LASTPIN (-3200 4800) BN 15
J 0
(-3250 4810);
DISPLAY 0.617021 (-3250 4810);
PAINT PINK (-3250 4810);
FORCEPROP 2 LAST CDS_LIB mstr_standard
J 2
(-3250 4800);
DISPLAY 0.787234 (-3250 4800);
PAINT MONO (-3250 4800);
DISPLAY INVISIBLE (-3250 4800);
FORCEPROP 1 LAST BODY_TYPE PLUMBING
J 0
(-3250 4750);
DISPLAY 1.234043 (-3250 4750);
PAINT GREEN (-3250 4750);
DISPLAY INVISIBLE (-3250 4750);
FORCEPROP 1 LAST HDL_TAP TRUE
J 0
(-2925 4675);
DISPLAY 1.234043 (-2925 4675);
PAINT GREEN (-2925 4675);
DISPLAY INVISIBLE (-2925 4675);
FORCEPROP 1 LAST PATH I114
J 0
(-3250 4800);
DISPLAY 0.936170 (-3250 4800);
PAINT GREEN (-3250 4800);
DISPLAY INVISIBLE (-3250 4800);
FORCEADD TAP..6
(-3250 4750);
FORCEPROP 3 LASTPIN (-3200 4750) SIG_NAME M_M_MA<14>
J 0
(-3190 4760);
DISPLAY 0.659574 (-3190 4760);
PAINT MONO (-3190 4760);
DISPLAY INVISIBLE (-3190 4760);
FORCEPROP 1 LASTPIN (-3200 4750) BN 14
J 0
(-3250 4760);
DISPLAY 0.617021 (-3250 4760);
PAINT PINK (-3250 4760);
FORCEPROP 2 LAST CDS_LIB mstr_standard
J 2
(-3250 4750);
DISPLAY 0.787234 (-3250 4750);
PAINT MONO (-3250 4750);
DISPLAY INVISIBLE (-3250 4750);
FORCEPROP 1 LAST BODY_TYPE PLUMBING
J 0
(-3250 4700);
DISPLAY 1.234043 (-3250 4700);
PAINT GREEN (-3250 4700);
DISPLAY INVISIBLE (-3250 4700);
FORCEPROP 1 LAST HDL_TAP TRUE
J 0
(-2925 4625);
DISPLAY 1.234043 (-2925 4625);
PAINT GREEN (-2925 4625);
DISPLAY INVISIBLE (-2925 4625);
FORCEPROP 1 LAST PATH I115
J 0
(-3250 4750);
DISPLAY 0.936170 (-3250 4750);
PAINT GREEN (-3250 4750);
DISPLAY INVISIBLE (-3250 4750);
FORCEADD TAP..6
(-3250 4700);
FORCEPROP 3 LASTPIN (-3200 4700) SIG_NAME M_M_MA<13>
J 0
(-3190 4710);
DISPLAY 0.659574 (-3190 4710);
PAINT MONO (-3190 4710);
DISPLAY INVISIBLE (-3190 4710);
FORCEPROP 1 LASTPIN (-3200 4700) BN 13
J 0
(-3250 4710);
DISPLAY 0.617021 (-3250 4710);
PAINT PINK (-3250 4710);
FORCEPROP 2 LAST CDS_LIB mstr_standard
J 2
(-3250 4700);
DISPLAY 0.787234 (-3250 4700);
PAINT MONO (-3250 4700);
DISPLAY INVISIBLE (-3250 4700);
FORCEPROP 1 LAST BODY_TYPE PLUMBING
J 0
(-3250 4650);
DISPLAY 1.234043 (-3250 4650);
PAINT GREEN (-3250 4650);
DISPLAY INVISIBLE (-3250 4650);
FORCEPROP 1 LAST HDL_TAP TRUE
J 0
(-2925 4575);
DISPLAY 1.234043 (-2925 4575);
PAINT GREEN (-2925 4575);
DISPLAY INVISIBLE (-2925 4575);
FORCEPROP 1 LAST PATH I116
J 0
(-3250 4700);
DISPLAY 0.936170 (-3250 4700);
PAINT GREEN (-3250 4700);
DISPLAY INVISIBLE (-3250 4700);
FORCEADD TAP..6
(-3250 4650);
FORCEPROP 3 LASTPIN (-3200 4650) SIG_NAME M_M_MA<12>
J 0
(-3190 4660);
DISPLAY 0.659574 (-3190 4660);
PAINT MONO (-3190 4660);
DISPLAY INVISIBLE (-3190 4660);
FORCEPROP 1 LASTPIN (-3200 4650) BN 12
J 0
(-3250 4660);
DISPLAY 0.617021 (-3250 4660);
PAINT PINK (-3250 4660);
FORCEPROP 2 LAST CDS_LIB mstr_standard
J 2
(-3250 4650);
DISPLAY 0.787234 (-3250 4650);
PAINT MONO (-3250 4650);
DISPLAY INVISIBLE (-3250 4650);
FORCEPROP 1 LAST BODY_TYPE PLUMBING
J 0
(-3250 4600);
DISPLAY 1.234043 (-3250 4600);
PAINT GREEN (-3250 4600);
DISPLAY INVISIBLE (-3250 4600);
FORCEPROP 1 LAST HDL_TAP TRUE
J 0
(-2925 4525);
DISPLAY 1.234043 (-2925 4525);
PAINT GREEN (-2925 4525);
DISPLAY INVISIBLE (-2925 4525);
FORCEPROP 1 LAST PATH I117
J 0
(-3250 4650);
DISPLAY 0.936170 (-3250 4650);
PAINT GREEN (-3250 4650);
DISPLAY INVISIBLE (-3250 4650);
FORCEADD TAP..6
(-3250 4600);
FORCEPROP 3 LASTPIN (-3200 4600) SIG_NAME M_M_MA<11>
J 0
(-3190 4610);
DISPLAY 0.659574 (-3190 4610);
PAINT MONO (-3190 4610);
DISPLAY INVISIBLE (-3190 4610);
FORCEPROP 1 LASTPIN (-3200 4600) BN 11
J 0
(-3250 4610);
DISPLAY 0.617021 (-3250 4610);
PAINT PINK (-3250 4610);
FORCEPROP 2 LAST CDS_LIB mstr_standard
J 2
(-3250 4600);
DISPLAY 0.787234 (-3250 4600);
PAINT MONO (-3250 4600);
DISPLAY INVISIBLE (-3250 4600);
FORCEPROP 1 LAST BODY_TYPE PLUMBING
J 0
(-3250 4550);
DISPLAY 1.234043 (-3250 4550);
PAINT GREEN (-3250 4550);
DISPLAY INVISIBLE (-3250 4550);
FORCEPROP 1 LAST HDL_TAP TRUE
J 0
(-2925 4475);
DISPLAY 1.234043 (-2925 4475);
PAINT GREEN (-2925 4475);
DISPLAY INVISIBLE (-2925 4475);
FORCEPROP 1 LAST PATH I118
J 0
(-3250 4600);
DISPLAY 0.936170 (-3250 4600);
PAINT GREEN (-3250 4600);
DISPLAY INVISIBLE (-3250 4600);
FORCEADD TAP..6
(-3250 4550);
FORCEPROP 3 LASTPIN (-3200 4550) SIG_NAME M_M_MA<10>
J 0
(-3190 4560);
DISPLAY 0.659574 (-3190 4560);
PAINT MONO (-3190 4560);
DISPLAY INVISIBLE (-3190 4560);
FORCEPROP 1 LASTPIN (-3200 4550) BN 10
J 0
(-3250 4560);
DISPLAY 0.617021 (-3250 4560);
PAINT PINK (-3250 4560);
FORCEPROP 2 LAST CDS_LIB mstr_standard
J 2
(-3250 4550);
DISPLAY 0.787234 (-3250 4550);
PAINT MONO (-3250 4550);
DISPLAY INVISIBLE (-3250 4550);
FORCEPROP 1 LAST BODY_TYPE PLUMBING
J 0
(-3250 4500);
DISPLAY 1.234043 (-3250 4500);
PAINT GREEN (-3250 4500);
DISPLAY INVISIBLE (-3250 4500);
FORCEPROP 1 LAST HDL_TAP TRUE
J 0
(-2925 4425);
DISPLAY 1.234043 (-2925 4425);
PAINT GREEN (-2925 4425);
DISPLAY INVISIBLE (-2925 4425);
FORCEPROP 1 LAST PATH I119
J 0
(-3250 4550);
DISPLAY 0.936170 (-3250 4550);
PAINT GREEN (-3250 4550);
DISPLAY INVISIBLE (-3250 4550);
FORCEADD TAP..6
R 2
(900 4500);
FORCEPROP 3 LASTPIN (850 4500) SIG_NAME M_M_DQS_DN<11>
J 0
(860 4510);
DISPLAY 0.659574 (860 4510);
PAINT MONO (860 4510);
DISPLAY INVISIBLE (860 4510);
FORCEPROP 1 LASTPIN (850 4500) BN 11
J 2
(900 4510);
DISPLAY 0.617021 (900 4510);
PAINT PINK (900 4510);
FORCEPROP 2 LAST CDS_LIB mstr_standard
J 0
(900 4500);
DISPLAY 0.787234 (900 4500);
PAINT MONO (900 4500);
DISPLAY INVISIBLE (900 4500);
FORCEPROP 1 LAST BODY_TYPE PLUMBING
J 2
(900 4450);
DISPLAY 1.234043 (900 4450);
PAINT GREEN (900 4450);
DISPLAY INVISIBLE (900 4450);
FORCEPROP 1 LAST HDL_TAP TRUE
J 2
(575 4375);
DISPLAY 1.234043 (575 4375);
PAINT GREEN (575 4375);
DISPLAY INVISIBLE (575 4375);
FORCEPROP 1 LAST PATH I12
J 2
(900 4500);
DISPLAY 0.936170 (900 4500);
PAINT GREEN (900 4500);
DISPLAY INVISIBLE (900 4500);
FORCEADD TAP..6
(-3250 4450);
FORCEPROP 3 LASTPIN (-3200 4450) SIG_NAME M_M_MA<8>
J 0
(-3190 4460);
DISPLAY 0.659574 (-3190 4460);
PAINT MONO (-3190 4460);
DISPLAY INVISIBLE (-3190 4460);
FORCEPROP 1 LASTPIN (-3200 4450) BN 8
J 0
(-3250 4460);
DISPLAY 0.617021 (-3250 4460);
PAINT PINK (-3250 4460);
FORCEPROP 2 LAST CDS_LIB mstr_standard
J 2
(-3250 4450);
DISPLAY 0.787234 (-3250 4450);
PAINT MONO (-3250 4450);
DISPLAY INVISIBLE (-3250 4450);
FORCEPROP 1 LAST BODY_TYPE PLUMBING
J 0
(-3250 4400);
DISPLAY 1.234043 (-3250 4400);
PAINT GREEN (-3250 4400);
DISPLAY INVISIBLE (-3250 4400);
FORCEPROP 1 LAST HDL_TAP TRUE
J 0
(-2925 4325);
DISPLAY 1.234043 (-2925 4325);
PAINT GREEN (-2925 4325);
DISPLAY INVISIBLE (-2925 4325);
FORCEPROP 1 LAST PATH I120
J 0
(-3250 4450);
DISPLAY 0.936170 (-3250 4450);
PAINT GREEN (-3250 4450);
DISPLAY INVISIBLE (-3250 4450);
FORCEADD TAP..6
(-3250 4500);
FORCEPROP 3 LASTPIN (-3200 4500) SIG_NAME M_M_MA<9>
J 0
(-3190 4510);
DISPLAY 0.659574 (-3190 4510);
PAINT MONO (-3190 4510);
DISPLAY INVISIBLE (-3190 4510);
FORCEPROP 1 LASTPIN (-3200 4500) BN 9
J 0
(-3250 4510);
DISPLAY 0.617021 (-3250 4510);
PAINT PINK (-3250 4510);
FORCEPROP 2 LAST CDS_LIB mstr_standard
J 2
(-3250 4500);
DISPLAY 0.787234 (-3250 4500);
PAINT MONO (-3250 4500);
DISPLAY INVISIBLE (-3250 4500);
FORCEPROP 1 LAST BODY_TYPE PLUMBING
J 0
(-3250 4450);
DISPLAY 1.234043 (-3250 4450);
PAINT GREEN (-3250 4450);
DISPLAY INVISIBLE (-3250 4450);
FORCEPROP 1 LAST HDL_TAP TRUE
J 0
(-2925 4375);
DISPLAY 1.234043 (-2925 4375);
PAINT GREEN (-2925 4375);
DISPLAY INVISIBLE (-2925 4375);
FORCEPROP 1 LAST PATH I121
J 0
(-3250 4500);
DISPLAY 0.936170 (-3250 4500);
PAINT GREEN (-3250 4500);
DISPLAY INVISIBLE (-3250 4500);
FORCEADD TAP..6
(-3250 4400);
FORCEPROP 3 LASTPIN (-3200 4400) SIG_NAME M_M_MA<7>
J 0
(-3190 4410);
DISPLAY 0.659574 (-3190 4410);
PAINT MONO (-3190 4410);
DISPLAY INVISIBLE (-3190 4410);
FORCEPROP 1 LASTPIN (-3200 4400) BN 7
J 0
(-3250 4410);
DISPLAY 0.617021 (-3250 4410);
PAINT PINK (-3250 4410);
FORCEPROP 2 LAST CDS_LIB mstr_standard
J 2
(-3250 4400);
DISPLAY 0.787234 (-3250 4400);
PAINT MONO (-3250 4400);
DISPLAY INVISIBLE (-3250 4400);
FORCEPROP 1 LAST BODY_TYPE PLUMBING
J 0
(-3250 4350);
DISPLAY 1.234043 (-3250 4350);
PAINT GREEN (-3250 4350);
DISPLAY INVISIBLE (-3250 4350);
FORCEPROP 1 LAST HDL_TAP TRUE
J 0
(-2925 4275);
DISPLAY 1.234043 (-2925 4275);
PAINT GREEN (-2925 4275);
DISPLAY INVISIBLE (-2925 4275);
FORCEPROP 1 LAST PATH I122
J 0
(-3250 4400);
DISPLAY 0.936170 (-3250 4400);
PAINT GREEN (-3250 4400);
DISPLAY INVISIBLE (-3250 4400);
FORCEADD TAP..6
(-3250 4350);
FORCEPROP 3 LASTPIN (-3200 4350) SIG_NAME M_M_MA<6>
J 0
(-3190 4360);
DISPLAY 0.659574 (-3190 4360);
PAINT MONO (-3190 4360);
DISPLAY INVISIBLE (-3190 4360);
FORCEPROP 1 LASTPIN (-3200 4350) BN 6
J 0
(-3250 4360);
DISPLAY 0.617021 (-3250 4360);
PAINT PINK (-3250 4360);
FORCEPROP 2 LAST CDS_LIB mstr_standard
J 2
(-3250 4350);
DISPLAY 0.787234 (-3250 4350);
PAINT MONO (-3250 4350);
DISPLAY INVISIBLE (-3250 4350);
FORCEPROP 1 LAST BODY_TYPE PLUMBING
J 0
(-3250 4300);
DISPLAY 1.234043 (-3250 4300);
PAINT GREEN (-3250 4300);
DISPLAY INVISIBLE (-3250 4300);
FORCEPROP 1 LAST HDL_TAP TRUE
J 0
(-2925 4225);
DISPLAY 1.234043 (-2925 4225);
PAINT GREEN (-2925 4225);
DISPLAY INVISIBLE (-2925 4225);
FORCEPROP 1 LAST PATH I123
J 0
(-3250 4350);
DISPLAY 0.936170 (-3250 4350);
PAINT GREEN (-3250 4350);
DISPLAY INVISIBLE (-3250 4350);
FORCEADD TAP..6
(-3250 4300);
FORCEPROP 3 LASTPIN (-3200 4300) SIG_NAME M_M_MA<5>
J 0
(-3190 4310);
DISPLAY 0.659574 (-3190 4310);
PAINT MONO (-3190 4310);
DISPLAY INVISIBLE (-3190 4310);
FORCEPROP 1 LASTPIN (-3200 4300) BN 5
J 0
(-3250 4310);
DISPLAY 0.617021 (-3250 4310);
PAINT PINK (-3250 4310);
FORCEPROP 2 LAST CDS_LIB mstr_standard
J 2
(-3250 4300);
DISPLAY 0.787234 (-3250 4300);
PAINT MONO (-3250 4300);
DISPLAY INVISIBLE (-3250 4300);
FORCEPROP 1 LAST BODY_TYPE PLUMBING
J 0
(-3250 4250);
DISPLAY 1.234043 (-3250 4250);
PAINT GREEN (-3250 4250);
DISPLAY INVISIBLE (-3250 4250);
FORCEPROP 1 LAST HDL_TAP TRUE
J 0
(-2925 4175);
DISPLAY 1.234043 (-2925 4175);
PAINT GREEN (-2925 4175);
DISPLAY INVISIBLE (-2925 4175);
FORCEPROP 1 LAST PATH I124
J 0
(-3250 4300);
DISPLAY 0.936170 (-3250 4300);
PAINT GREEN (-3250 4300);
DISPLAY INVISIBLE (-3250 4300);
FORCEADD TAP..6
(-3250 4250);
FORCEPROP 3 LASTPIN (-3200 4250) SIG_NAME M_M_MA<4>
J 0
(-3190 4260);
DISPLAY 0.659574 (-3190 4260);
PAINT MONO (-3190 4260);
DISPLAY INVISIBLE (-3190 4260);
FORCEPROP 1 LASTPIN (-3200 4250) BN 4
J 0
(-3250 4260);
DISPLAY 0.617021 (-3250 4260);
PAINT PINK (-3250 4260);
FORCEPROP 2 LAST CDS_LIB mstr_standard
J 2
(-3250 4250);
DISPLAY 0.787234 (-3250 4250);
PAINT MONO (-3250 4250);
DISPLAY INVISIBLE (-3250 4250);
FORCEPROP 1 LAST BODY_TYPE PLUMBING
J 0
(-3250 4200);
DISPLAY 1.234043 (-3250 4200);
PAINT GREEN (-3250 4200);
DISPLAY INVISIBLE (-3250 4200);
FORCEPROP 1 LAST HDL_TAP TRUE
J 0
(-2925 4125);
DISPLAY 1.234043 (-2925 4125);
PAINT GREEN (-2925 4125);
DISPLAY INVISIBLE (-2925 4125);
FORCEPROP 1 LAST PATH I125
J 0
(-3250 4250);
DISPLAY 0.936170 (-3250 4250);
PAINT GREEN (-3250 4250);
DISPLAY INVISIBLE (-3250 4250);
FORCEADD TAP..6
(-3250 4200);
FORCEPROP 3 LASTPIN (-3200 4200) SIG_NAME M_M_MA<3>
J 0
(-3190 4210);
DISPLAY 0.659574 (-3190 4210);
PAINT MONO (-3190 4210);
DISPLAY INVISIBLE (-3190 4210);
FORCEPROP 1 LASTPIN (-3200 4200) BN 3
J 0
(-3250 4210);
DISPLAY 0.617021 (-3250 4210);
PAINT PINK (-3250 4210);
FORCEPROP 2 LAST CDS_LIB mstr_standard
J 2
(-3250 4200);
DISPLAY 0.787234 (-3250 4200);
PAINT MONO (-3250 4200);
DISPLAY INVISIBLE (-3250 4200);
FORCEPROP 1 LAST BODY_TYPE PLUMBING
J 0
(-3250 4150);
DISPLAY 1.234043 (-3250 4150);
PAINT GREEN (-3250 4150);
DISPLAY INVISIBLE (-3250 4150);
FORCEPROP 1 LAST HDL_TAP TRUE
J 0
(-2925 4075);
DISPLAY 1.234043 (-2925 4075);
PAINT GREEN (-2925 4075);
DISPLAY INVISIBLE (-2925 4075);
FORCEPROP 1 LAST PATH I126
J 0
(-3250 4200);
DISPLAY 0.936170 (-3250 4200);
PAINT GREEN (-3250 4200);
DISPLAY INVISIBLE (-3250 4200);
FORCEADD TAP..6
(-3250 4150);
FORCEPROP 3 LASTPIN (-3200 4150) SIG_NAME M_M_MA<2>
J 0
(-3190 4160);
DISPLAY 0.659574 (-3190 4160);
PAINT MONO (-3190 4160);
DISPLAY INVISIBLE (-3190 4160);
FORCEPROP 1 LASTPIN (-3200 4150) BN 2
J 0
(-3250 4160);
DISPLAY 0.617021 (-3250 4160);
PAINT PINK (-3250 4160);
FORCEPROP 2 LAST CDS_LIB mstr_standard
J 2
(-3250 4150);
DISPLAY 0.787234 (-3250 4150);
PAINT MONO (-3250 4150);
DISPLAY INVISIBLE (-3250 4150);
FORCEPROP 1 LAST BODY_TYPE PLUMBING
J 0
(-3250 4100);
DISPLAY 1.234043 (-3250 4100);
PAINT GREEN (-3250 4100);
DISPLAY INVISIBLE (-3250 4100);
FORCEPROP 1 LAST HDL_TAP TRUE
J 0
(-2925 4025);
DISPLAY 1.234043 (-2925 4025);
PAINT GREEN (-2925 4025);
DISPLAY INVISIBLE (-2925 4025);
FORCEPROP 1 LAST PATH I127
J 0
(-3250 4150);
DISPLAY 0.936170 (-3250 4150);
PAINT GREEN (-3250 4150);
DISPLAY INVISIBLE (-3250 4150);
FORCEADD TAP..6
(-3250 4100);
FORCEPROP 3 LASTPIN (-3200 4100) SIG_NAME M_M_MA<1>
J 0
(-3190 4110);
DISPLAY 0.659574 (-3190 4110);
PAINT MONO (-3190 4110);
DISPLAY INVISIBLE (-3190 4110);
FORCEPROP 1 LASTPIN (-3200 4100) BN 1
J 0
(-3250 4110);
DISPLAY 0.617021 (-3250 4110);
PAINT PINK (-3250 4110);
FORCEPROP 2 LAST CDS_LIB mstr_standard
J 2
(-3250 4100);
DISPLAY 0.787234 (-3250 4100);
PAINT MONO (-3250 4100);
DISPLAY INVISIBLE (-3250 4100);
FORCEPROP 1 LAST BODY_TYPE PLUMBING
J 0
(-3250 4050);
DISPLAY 1.234043 (-3250 4050);
PAINT GREEN (-3250 4050);
DISPLAY INVISIBLE (-3250 4050);
FORCEPROP 1 LAST HDL_TAP TRUE
J 0
(-2925 3975);
DISPLAY 1.234043 (-2925 3975);
PAINT GREEN (-2925 3975);
DISPLAY INVISIBLE (-2925 3975);
FORCEPROP 1 LAST PATH I128
J 0
(-3250 4100);
DISPLAY 0.936170 (-3250 4100);
PAINT GREEN (-3250 4100);
DISPLAY INVISIBLE (-3250 4100);
FORCEADD TAP..6
(-3250 4050);
FORCEPROP 3 LASTPIN (-3200 4050) SIG_NAME M_M_MA<0>
J 0
(-3190 4060);
DISPLAY 0.659574 (-3190 4060);
PAINT MONO (-3190 4060);
DISPLAY INVISIBLE (-3190 4060);
FORCEPROP 1 LASTPIN (-3200 4050) BN 0
J 0
(-3250 4060);
DISPLAY 0.617021 (-3250 4060);
PAINT PINK (-3250 4060);
FORCEPROP 2 LAST CDS_LIB mstr_standard
J 2
(-3250 4050);
DISPLAY 0.787234 (-3250 4050);
PAINT MONO (-3250 4050);
DISPLAY INVISIBLE (-3250 4050);
FORCEPROP 1 LAST BODY_TYPE PLUMBING
J 0
(-3250 4000);
DISPLAY 1.234043 (-3250 4000);
PAINT GREEN (-3250 4000);
DISPLAY INVISIBLE (-3250 4000);
FORCEPROP 1 LAST HDL_TAP TRUE
J 0
(-2925 3925);
DISPLAY 1.234043 (-2925 3925);
PAINT GREEN (-2925 3925);
DISPLAY INVISIBLE (-2925 3925);
FORCEPROP 1 LAST PATH I129
J 0
(-3250 4050);
DISPLAY 0.936170 (-3250 4050);
PAINT GREEN (-3250 4050);
DISPLAY INVISIBLE (-3250 4050);
FORCEADD TAP..6
R 2
(900 4400);
FORCEPROP 3 LASTPIN (850 4400) SIG_NAME M_M_DQS_DN<10>
J 0
(860 4410);
DISPLAY 0.659574 (860 4410);
PAINT MONO (860 4410);
DISPLAY INVISIBLE (860 4410);
FORCEPROP 1 LASTPIN (850 4400) BN 10
J 2
(900 4410);
DISPLAY 0.617021 (900 4410);
PAINT PINK (900 4410);
FORCEPROP 2 LAST CDS_LIB mstr_standard
J 0
(900 4400);
DISPLAY 0.787234 (900 4400);
PAINT MONO (900 4400);
DISPLAY INVISIBLE (900 4400);
FORCEPROP 1 LAST BODY_TYPE PLUMBING
J 2
(900 4350);
DISPLAY 1.234043 (900 4350);
PAINT GREEN (900 4350);
DISPLAY INVISIBLE (900 4350);
FORCEPROP 1 LAST HDL_TAP TRUE
J 2
(575 4275);
DISPLAY 1.234043 (575 4275);
PAINT GREEN (575 4275);
DISPLAY INVISIBLE (575 4275);
FORCEPROP 1 LAST PATH I13
J 2
(900 4400);
DISPLAY 0.936170 (900 4400);
PAINT GREEN (900 4400);
DISPLAY INVISIBLE (900 4400);
FORCEADD TAP..6
(-3250 3950);
FORCEPROP 3 LASTPIN (-3200 3950) SIG_NAME M_M_BA<1>
J 0
(-3190 3960);
DISPLAY 0.659574 (-3190 3960);
PAINT MONO (-3190 3960);
DISPLAY INVISIBLE (-3190 3960);
FORCEPROP 1 LASTPIN (-3200 3950) BN 1
J 0
(-3250 3960);
DISPLAY 0.617021 (-3250 3960);
PAINT PINK (-3250 3960);
FORCEPROP 2 LAST CDS_LIB mstr_standard
J 0
(-3250 3950);
DISPLAY 0.787234 (-3250 3950);
PAINT MONO (-3250 3950);
DISPLAY INVISIBLE (-3250 3950);
FORCEPROP 1 LAST BODY_TYPE PLUMBING
J 0
(-3250 3900);
DISPLAY 1.234043 (-3250 3900);
PAINT GREEN (-3250 3900);
DISPLAY INVISIBLE (-3250 3900);
FORCEPROP 1 LAST HDL_TAP TRUE
J 0
(-2925 3825);
DISPLAY 1.234043 (-2925 3825);
PAINT GREEN (-2925 3825);
DISPLAY INVISIBLE (-2925 3825);
FORCEPROP 1 LAST PATH I130
J 0
(-3250 3950);
DISPLAY 0.936170 (-3250 3950);
PAINT GREEN (-3250 3950);
DISPLAY INVISIBLE (-3250 3950);
FORCEADD OFFPAGE..1
(-3850 4950);
FORCEPROP 2 LAST $XR0 62 
J 0
(-4101 4950);
DISPLAY 0.638298 (-4101 4950);
PAINT MONO (-4101 4950);
FORCEPROP 2 LAST $XR1 88 
J 0
(-4191 4950);
DISPLAY 0.638298 (-4191 4950);
PAINT MONO (-4191 4950);
FORCEPROP 2 LAST CDS_LIB mstr_standard
J 0
(-3850 4950);
DISPLAY 0.787234 (-3850 4950);
PAINT MONO (-3850 4950);
DISPLAY INVISIBLE (-3850 4950);
FORCEPROP 1 LAST OFFPAGE TRUE
J 0
(-3525 4825);
DISPLAY 0.936170 (-3525 4825);
PAINT GREEN (-3525 4825);
DISPLAY INVISIBLE (-3525 4825);
FORCEPROP 1 LAST COMMENT_BODY TRUE
J 0
(-3725 4850);
DISPLAY 0.936170 (-3725 4850);
PAINT GREEN (-3725 4850);
DISPLAY INVISIBLE (-3725 4850);
FORCEPROP 2 LAST PATH I131
J 0
(-3800 5025);
DISPLAY 0.787234 (-3800 5025);
PAINT MONO (-3800 5025);
DISPLAY INVISIBLE (-3800 5025);
FORCEADD OFFPAGE..1
(-3850 4000);
FORCEPROP 2 LAST $XR0 62 
J 0
(-4101 4000);
DISPLAY 0.638298 (-4101 4000);
PAINT MONO (-4101 4000);
FORCEPROP 2 LAST $XR1 88 
J 0
(-4191 4000);
DISPLAY 0.638298 (-4191 4000);
PAINT MONO (-4191 4000);
FORCEPROP 2 LAST CDS_LIB mstr_standard
J 0
(-3850 4000);
DISPLAY 0.787234 (-3850 4000);
PAINT MONO (-3850 4000);
DISPLAY INVISIBLE (-3850 4000);
FORCEPROP 1 LAST OFFPAGE TRUE
J 0
(-3525 3875);
DISPLAY 0.936170 (-3525 3875);
PAINT GREEN (-3525 3875);
DISPLAY INVISIBLE (-3525 3875);
FORCEPROP 1 LAST COMMENT_BODY TRUE
J 0
(-3725 3900);
DISPLAY 0.936170 (-3725 3900);
PAINT GREEN (-3725 3900);
DISPLAY INVISIBLE (-3725 3900);
FORCEPROP 2 LAST PATH I132
J 0
(-3800 4075);
DISPLAY 0.787234 (-3800 4075);
PAINT MONO (-3800 4075);
DISPLAY INVISIBLE (-3800 4075);
FORCEADD TAP..6
(-3250 3900);
FORCEPROP 3 LASTPIN (-3200 3900) SIG_NAME M_M_BA<0>
J 0
(-3190 3910);
DISPLAY 0.659574 (-3190 3910);
PAINT MONO (-3190 3910);
DISPLAY INVISIBLE (-3190 3910);
FORCEPROP 1 LASTPIN (-3200 3900) BN 0
J 0
(-3250 3910);
DISPLAY 0.617021 (-3250 3910);
PAINT PINK (-3250 3910);
FORCEPROP 2 LAST CDS_LIB mstr_standard
J 0
(-3250 3900);
DISPLAY 0.787234 (-3250 3900);
PAINT MONO (-3250 3900);
DISPLAY INVISIBLE (-3250 3900);
FORCEPROP 1 LAST BODY_TYPE PLUMBING
J 0
(-3250 3850);
DISPLAY 1.234043 (-3250 3850);
PAINT GREEN (-3250 3850);
DISPLAY INVISIBLE (-3250 3850);
FORCEPROP 1 LAST HDL_TAP TRUE
J 0
(-2925 3775);
DISPLAY 1.234043 (-2925 3775);
PAINT GREEN (-2925 3775);
DISPLAY INVISIBLE (-2925 3775);
FORCEPROP 1 LAST PATH I133
J 0
(-3250 3900);
DISPLAY 0.936170 (-3250 3900);
PAINT GREEN (-3250 3900);
DISPLAY INVISIBLE (-3250 3900);
FORCEADD TAP..6
(-3250 3800);
FORCEPROP 3 LASTPIN (-3200 3800) SIG_NAME M_M_BG<0>
J 0
(-3190 3810);
DISPLAY 0.659574 (-3190 3810);
PAINT MONO (-3190 3810);
DISPLAY INVISIBLE (-3190 3810);
FORCEPROP 1 LASTPIN (-3200 3800) BN 0
J 0
(-3250 3810);
DISPLAY 0.617021 (-3250 3810);
PAINT PINK (-3250 3810);
FORCEPROP 2 LAST CDS_LIB mstr_standard
J 0
(-3250 3800);
DISPLAY 0.787234 (-3250 3800);
PAINT MONO (-3250 3800);
DISPLAY INVISIBLE (-3250 3800);
FORCEPROP 1 LAST BODY_TYPE PLUMBING
J 0
(-3250 3750);
DISPLAY 1.234043 (-3250 3750);
PAINT GREEN (-3250 3750);
DISPLAY INVISIBLE (-3250 3750);
FORCEPROP 1 LAST HDL_TAP TRUE
J 0
(-2925 3675);
DISPLAY 1.234043 (-2925 3675);
PAINT GREEN (-2925 3675);
DISPLAY INVISIBLE (-2925 3675);
FORCEPROP 1 LAST PATH I134
J 0
(-3250 3800);
DISPLAY 0.936170 (-3250 3800);
PAINT GREEN (-3250 3800);
DISPLAY INVISIBLE (-3250 3800);
FORCEADD TAP..6
(-3250 3850);
FORCEPROP 3 LASTPIN (-3200 3850) SIG_NAME M_M_BG<1>
J 0
(-3190 3860);
DISPLAY 0.659574 (-3190 3860);
PAINT MONO (-3190 3860);
DISPLAY INVISIBLE (-3190 3860);
FORCEPROP 1 LASTPIN (-3200 3850) BN 1
J 0
(-3250 3860);
DISPLAY 0.617021 (-3250 3860);
PAINT PINK (-3250 3860);
FORCEPROP 2 LAST CDS_LIB mstr_standard
J 0
(-3250 3850);
DISPLAY 0.787234 (-3250 3850);
PAINT MONO (-3250 3850);
DISPLAY INVISIBLE (-3250 3850);
FORCEPROP 1 LAST BODY_TYPE PLUMBING
J 0
(-3250 3800);
DISPLAY 1.234043 (-3250 3800);
PAINT GREEN (-3250 3800);
DISPLAY INVISIBLE (-3250 3800);
FORCEPROP 1 LAST HDL_TAP TRUE
J 0
(-2925 3725);
DISPLAY 1.234043 (-2925 3725);
PAINT GREEN (-2925 3725);
DISPLAY INVISIBLE (-2925 3725);
FORCEPROP 1 LAST PATH I135
J 0
(-3250 3850);
DISPLAY 0.936170 (-3250 3850);
PAINT GREEN (-3250 3850);
DISPLAY INVISIBLE (-3250 3850);
FORCEADD OFFPAGE..1
(-3850 3500);
FORCEPROP 2 LAST $XR0 62 
J 0
(-4101 3500);
DISPLAY 0.638298 (-4101 3500);
PAINT MONO (-4101 3500);
FORCEPROP 2 LAST $XR1 88 
J 0
(-4191 3500);
DISPLAY 0.638298 (-4191 3500);
PAINT MONO (-4191 3500);
FORCEPROP 2 LAST CDS_LIB mstr_standard
J 0
(-3850 3500);
DISPLAY 0.787234 (-3850 3500);
PAINT MONO (-3850 3500);
DISPLAY INVISIBLE (-3850 3500);
FORCEPROP 1 LAST OFFPAGE TRUE
J 0
(-3525 3375);
DISPLAY 0.936170 (-3525 3375);
PAINT GREEN (-3525 3375);
DISPLAY INVISIBLE (-3525 3375);
FORCEPROP 1 LAST COMMENT_BODY TRUE
J 0
(-3725 3400);
DISPLAY 0.936170 (-3725 3400);
PAINT GREEN (-3725 3400);
DISPLAY INVISIBLE (-3725 3400);
FORCEPROP 2 LAST PATH I136
J 0
(-3800 3575);
DISPLAY 0.787234 (-3800 3575);
PAINT MONO (-3800 3575);
DISPLAY INVISIBLE (-3800 3575);
FORCEADD OFFPAGE..1
(-3850 3900);
FORCEPROP 2 LAST $XR0 62 
J 0
(-4101 3900);
DISPLAY 0.638298 (-4101 3900);
PAINT MONO (-4101 3900);
FORCEPROP 2 LAST $XR1 88 
J 0
(-4191 3900);
DISPLAY 0.638298 (-4191 3900);
PAINT MONO (-4191 3900);
FORCEPROP 2 LAST CDS_LIB mstr_standard
J 0
(-3850 3900);
DISPLAY 0.787234 (-3850 3900);
PAINT MONO (-3850 3900);
DISPLAY INVISIBLE (-3850 3900);
FORCEPROP 1 LAST OFFPAGE TRUE
J 0
(-3525 3775);
DISPLAY 0.936170 (-3525 3775);
PAINT GREEN (-3525 3775);
DISPLAY INVISIBLE (-3525 3775);
FORCEPROP 1 LAST COMMENT_BODY TRUE
J 0
(-3725 3800);
DISPLAY 0.936170 (-3725 3800);
PAINT GREEN (-3725 3800);
DISPLAY INVISIBLE (-3725 3800);
FORCEPROP 2 LAST PATH I137
J 0
(-3800 3975);
DISPLAY 0.787234 (-3800 3975);
PAINT MONO (-3800 3975);
DISPLAY INVISIBLE (-3800 3975);
FORCEADD TAP..6
(-3250 2800);
FORCEPROP 3 LASTPIN (-3200 2800) SIG_NAME M_M_ECC<7>
J 0
(-3190 2810);
DISPLAY 0.659574 (-3190 2810);
PAINT MONO (-3190 2810);
DISPLAY INVISIBLE (-3190 2810);
FORCEPROP 1 LASTPIN (-3200 2800) BN 7
J 0
(-3250 2810);
DISPLAY 0.617021 (-3250 2810);
PAINT PINK (-3250 2810);
FORCEPROP 2 LAST CDS_LIB mstr_standard
J 0
(-3250 2800);
DISPLAY 0.787234 (-3250 2800);
PAINT MONO (-3250 2800);
DISPLAY INVISIBLE (-3250 2800);
FORCEPROP 1 LAST BODY_TYPE PLUMBING
J 0
(-3250 2750);
DISPLAY 1.234043 (-3250 2750);
PAINT GREEN (-3250 2750);
DISPLAY INVISIBLE (-3250 2750);
FORCEPROP 1 LAST HDL_TAP TRUE
J 0
(-2925 2675);
DISPLAY 1.234043 (-2925 2675);
PAINT GREEN (-2925 2675);
DISPLAY INVISIBLE (-2925 2675);
FORCEPROP 1 LAST PATH I138
J 0
(-3250 2800);
DISPLAY 0.936170 (-3250 2800);
PAINT GREEN (-3250 2800);
DISPLAY INVISIBLE (-3250 2800);
FORCEADD TAP..6
(-3250 2850);
FORCEPROP 3 LASTPIN (-3200 2850) SIG_NAME M_M_ECC<6>
J 0
(-3190 2860);
DISPLAY 0.659574 (-3190 2860);
PAINT MONO (-3190 2860);
DISPLAY INVISIBLE (-3190 2860);
FORCEPROP 1 LASTPIN (-3200 2850) BN 6
J 0
(-3250 2860);
DISPLAY 0.617021 (-3250 2860);
PAINT PINK (-3250 2860);
FORCEPROP 2 LAST CDS_LIB mstr_standard
J 0
(-3250 2850);
DISPLAY 0.787234 (-3250 2850);
PAINT MONO (-3250 2850);
DISPLAY INVISIBLE (-3250 2850);
FORCEPROP 1 LAST BODY_TYPE PLUMBING
J 0
(-3250 2800);
DISPLAY 1.234043 (-3250 2800);
PAINT GREEN (-3250 2800);
DISPLAY INVISIBLE (-3250 2800);
FORCEPROP 1 LAST HDL_TAP TRUE
J 0
(-2925 2725);
DISPLAY 1.234043 (-2925 2725);
PAINT GREEN (-2925 2725);
DISPLAY INVISIBLE (-2925 2725);
FORCEPROP 1 LAST PATH I139
J 0
(-3250 2850);
DISPLAY 0.936170 (-3250 2850);
PAINT GREEN (-3250 2850);
DISPLAY INVISIBLE (-3250 2850);
FORCEADD TAP..6
R 2
(900 4300);
FORCEPROP 3 LASTPIN (850 4300) SIG_NAME M_M_DQS_DN<9>
J 0
(860 4310);
DISPLAY 0.659574 (860 4310);
PAINT MONO (860 4310);
DISPLAY INVISIBLE (860 4310);
FORCEPROP 1 LASTPIN (850 4300) BN 9
J 2
(900 4310);
DISPLAY 0.617021 (900 4310);
PAINT PINK (900 4310);
FORCEPROP 2 LAST CDS_LIB mstr_standard
J 0
(900 4300);
DISPLAY 0.787234 (900 4300);
PAINT MONO (900 4300);
DISPLAY INVISIBLE (900 4300);
FORCEPROP 1 LAST BODY_TYPE PLUMBING
J 2
(900 4250);
DISPLAY 1.234043 (900 4250);
PAINT GREEN (900 4250);
DISPLAY INVISIBLE (900 4250);
FORCEPROP 1 LAST HDL_TAP TRUE
J 2
(575 4175);
DISPLAY 1.234043 (575 4175);
PAINT GREEN (575 4175);
DISPLAY INVISIBLE (575 4175);
FORCEPROP 1 LAST PATH I14
J 2
(900 4300);
DISPLAY 0.936170 (900 4300);
PAINT GREEN (900 4300);
DISPLAY INVISIBLE (900 4300);
FORCEADD TAP..6
(-3250 2750);
FORCEPROP 3 LASTPIN (-3200 2750) SIG_NAME M_M_ECC<4>
J 0
(-3190 2760);
DISPLAY 0.659574 (-3190 2760);
PAINT MONO (-3190 2760);
DISPLAY INVISIBLE (-3190 2760);
FORCEPROP 1 LASTPIN (-3200 2750) BN 4
J 0
(-3250 2760);
DISPLAY 0.617021 (-3250 2760);
PAINT PINK (-3250 2760);
FORCEPROP 2 LAST CDS_LIB mstr_standard
J 0
(-3250 2750);
DISPLAY 0.787234 (-3250 2750);
PAINT MONO (-3250 2750);
DISPLAY INVISIBLE (-3250 2750);
FORCEPROP 1 LAST BODY_TYPE PLUMBING
J 0
(-3250 2700);
DISPLAY 1.234043 (-3250 2700);
PAINT GREEN (-3250 2700);
DISPLAY INVISIBLE (-3250 2700);
FORCEPROP 1 LAST HDL_TAP TRUE
J 0
(-2925 2625);
DISPLAY 1.234043 (-2925 2625);
PAINT GREEN (-2925 2625);
DISPLAY INVISIBLE (-2925 2625);
FORCEPROP 1 LAST PATH I140
J 0
(-3250 2750);
DISPLAY 0.936170 (-3250 2750);
PAINT GREEN (-3250 2750);
DISPLAY INVISIBLE (-3250 2750);
FORCEADD TAP..6
(-3250 2700);
FORCEPROP 3 LASTPIN (-3200 2700) SIG_NAME M_M_ECC<5>
J 0
(-3190 2710);
DISPLAY 0.659574 (-3190 2710);
PAINT MONO (-3190 2710);
DISPLAY INVISIBLE (-3190 2710);
FORCEPROP 1 LASTPIN (-3200 2700) BN 5
J 0
(-3250 2710);
DISPLAY 0.617021 (-3250 2710);
PAINT PINK (-3250 2710);
FORCEPROP 2 LAST CDS_LIB mstr_standard
J 0
(-3250 2700);
DISPLAY 0.787234 (-3250 2700);
PAINT MONO (-3250 2700);
DISPLAY INVISIBLE (-3250 2700);
FORCEPROP 1 LAST BODY_TYPE PLUMBING
J 0
(-3250 2650);
DISPLAY 1.234043 (-3250 2650);
PAINT GREEN (-3250 2650);
DISPLAY INVISIBLE (-3250 2650);
FORCEPROP 1 LAST HDL_TAP TRUE
J 0
(-2925 2575);
DISPLAY 1.234043 (-2925 2575);
PAINT GREEN (-2925 2575);
DISPLAY INVISIBLE (-2925 2575);
FORCEPROP 1 LAST PATH I141
J 0
(-3250 2700);
DISPLAY 0.936170 (-3250 2700);
PAINT GREEN (-3250 2700);
DISPLAY INVISIBLE (-3250 2700);
FORCEADD TAP..6
(-3250 2650);
FORCEPROP 3 LASTPIN (-3200 2650) SIG_NAME M_M_ECC<2>
J 0
(-3190 2660);
DISPLAY 0.659574 (-3190 2660);
PAINT MONO (-3190 2660);
DISPLAY INVISIBLE (-3190 2660);
FORCEPROP 1 LASTPIN (-3200 2650) BN 2
J 0
(-3250 2660);
DISPLAY 0.617021 (-3250 2660);
PAINT PINK (-3250 2660);
FORCEPROP 2 LAST CDS_LIB mstr_standard
J 0
(-3250 2650);
DISPLAY 0.787234 (-3250 2650);
PAINT MONO (-3250 2650);
DISPLAY INVISIBLE (-3250 2650);
FORCEPROP 1 LAST BODY_TYPE PLUMBING
J 0
(-3250 2600);
DISPLAY 1.234043 (-3250 2600);
PAINT GREEN (-3250 2600);
DISPLAY INVISIBLE (-3250 2600);
FORCEPROP 1 LAST HDL_TAP TRUE
J 0
(-2925 2525);
DISPLAY 1.234043 (-2925 2525);
PAINT GREEN (-2925 2525);
DISPLAY INVISIBLE (-2925 2525);
FORCEPROP 1 LAST PATH I142
J 0
(-3250 2650);
DISPLAY 0.936170 (-3250 2650);
PAINT GREEN (-3250 2650);
DISPLAY INVISIBLE (-3250 2650);
FORCEADD TAP..6
(-3250 2600);
FORCEPROP 3 LASTPIN (-3200 2600) SIG_NAME M_M_ECC<3>
J 0
(-3190 2610);
DISPLAY 0.659574 (-3190 2610);
PAINT MONO (-3190 2610);
DISPLAY INVISIBLE (-3190 2610);
FORCEPROP 1 LASTPIN (-3200 2600) BN 3
J 0
(-3250 2610);
DISPLAY 0.617021 (-3250 2610);
PAINT PINK (-3250 2610);
FORCEPROP 2 LAST CDS_LIB mstr_standard
J 0
(-3250 2600);
DISPLAY 0.787234 (-3250 2600);
PAINT MONO (-3250 2600);
DISPLAY INVISIBLE (-3250 2600);
FORCEPROP 1 LAST BODY_TYPE PLUMBING
J 0
(-3250 2550);
DISPLAY 1.234043 (-3250 2550);
PAINT GREEN (-3250 2550);
DISPLAY INVISIBLE (-3250 2550);
FORCEPROP 1 LAST HDL_TAP TRUE
J 0
(-2925 2475);
DISPLAY 1.234043 (-2925 2475);
PAINT GREEN (-2925 2475);
DISPLAY INVISIBLE (-2925 2475);
FORCEPROP 1 LAST PATH I143
J 0
(-3250 2600);
DISPLAY 0.936170 (-3250 2600);
PAINT GREEN (-3250 2600);
DISPLAY INVISIBLE (-3250 2600);
FORCEADD TAP..6
(-3250 2550);
FORCEPROP 3 LASTPIN (-3200 2550) SIG_NAME M_M_ECC<0>
J 0
(-3190 2560);
DISPLAY 0.659574 (-3190 2560);
PAINT MONO (-3190 2560);
DISPLAY INVISIBLE (-3190 2560);
FORCEPROP 1 LASTPIN (-3200 2550) BN 0
J 0
(-3250 2560);
DISPLAY 0.617021 (-3250 2560);
PAINT PINK (-3250 2560);
FORCEPROP 2 LAST CDS_LIB mstr_standard
J 0
(-3250 2550);
DISPLAY 0.787234 (-3250 2550);
PAINT MONO (-3250 2550);
DISPLAY INVISIBLE (-3250 2550);
FORCEPROP 1 LAST BODY_TYPE PLUMBING
J 0
(-3250 2500);
DISPLAY 1.234043 (-3250 2500);
PAINT GREEN (-3250 2500);
DISPLAY INVISIBLE (-3250 2500);
FORCEPROP 1 LAST HDL_TAP TRUE
J 0
(-2925 2425);
DISPLAY 1.234043 (-2925 2425);
PAINT GREEN (-2925 2425);
DISPLAY INVISIBLE (-2925 2425);
FORCEPROP 1 LAST PATH I144
J 0
(-3250 2550);
DISPLAY 0.936170 (-3250 2550);
PAINT GREEN (-3250 2550);
DISPLAY INVISIBLE (-3250 2550);
FORCEADD TAP..6
(-3250 2500);
FORCEPROP 3 LASTPIN (-3200 2500) SIG_NAME M_M_ECC<1>
J 0
(-3190 2510);
DISPLAY 0.659574 (-3190 2510);
PAINT MONO (-3190 2510);
DISPLAY INVISIBLE (-3190 2510);
FORCEPROP 1 LASTPIN (-3200 2500) BN 1
J 0
(-3250 2510);
DISPLAY 0.617021 (-3250 2510);
PAINT PINK (-3250 2510);
FORCEPROP 2 LAST CDS_LIB mstr_standard
J 0
(-3250 2500);
DISPLAY 0.787234 (-3250 2500);
PAINT MONO (-3250 2500);
DISPLAY INVISIBLE (-3250 2500);
FORCEPROP 1 LAST BODY_TYPE PLUMBING
J 0
(-3250 2450);
DISPLAY 1.234043 (-3250 2450);
PAINT GREEN (-3250 2450);
DISPLAY INVISIBLE (-3250 2450);
FORCEPROP 1 LAST HDL_TAP TRUE
J 0
(-2925 2375);
DISPLAY 1.234043 (-2925 2375);
PAINT GREEN (-2925 2375);
DISPLAY INVISIBLE (-2925 2375);
FORCEPROP 1 LAST PATH I145
J 0
(-3250 2500);
DISPLAY 0.936170 (-3250 2500);
PAINT GREEN (-3250 2500);
DISPLAY INVISIBLE (-3250 2500);
FORCEADD OFFPAGE..1
(-3850 2850);
FORCEPROP 2 LAST $XR0 62 
J 0
(-4101 2850);
DISPLAY 0.638298 (-4101 2850);
PAINT MONO (-4101 2850);
FORCEPROP 2 LAST $XR1 88 
J 0
(-4191 2850);
DISPLAY 0.638298 (-4191 2850);
PAINT MONO (-4191 2850);
FORCEPROP 2 LAST CDS_LIB mstr_standard
J 0
(-3850 2850);
DISPLAY 0.787234 (-3850 2850);
PAINT MONO (-3850 2850);
DISPLAY INVISIBLE (-3850 2850);
FORCEPROP 1 LAST OFFPAGE TRUE
J 0
(-3525 2725);
DISPLAY 0.936170 (-3525 2725);
PAINT GREEN (-3525 2725);
DISPLAY INVISIBLE (-3525 2725);
FORCEPROP 1 LAST COMMENT_BODY TRUE
J 0
(-3725 2750);
DISPLAY 0.936170 (-3725 2750);
PAINT GREEN (-3725 2750);
DISPLAY INVISIBLE (-3725 2750);
FORCEPROP 2 LAST PATH I146
J 0
(-3800 2925);
DISPLAY 0.787234 (-3800 2925);
PAINT MONO (-3800 2925);
DISPLAY INVISIBLE (-3800 2925);
FORCEADD OFFPAGE..1
(-3850 2800);
FORCEPROP 2 LAST $XR0 55 
J 0
(-4101 2800);
DISPLAY 0.638298 (-4101 2800);
PAINT MONO (-4101 2800);
FORCEPROP 2 LAST $XR1 83 
J 0
(-4191 2800);
DISPLAY 0.638298 (-4191 2800);
PAINT MONO (-4191 2800);
FORCEPROP 2 LAST $XR2 84 
J 0
(-4281 2800);
DISPLAY 0.638298 (-4281 2800);
PAINT MONO (-4281 2800);
FORCEPROP 2 LAST $XR3 85 
J 0
(-4371 2800);
DISPLAY 0.638298 (-4371 2800);
PAINT MONO (-4371 2800);
FORCEPROP 2 LAST $XR4 86 
J 0
(-4461 2800);
DISPLAY 0.638298 (-4461 2800);
PAINT MONO (-4461 2800);
FORCEPROP 2 LAST $XR5 88 
J 0
(-4551 2800);
DISPLAY 0.638298 (-4551 2800);
PAINT MONO (-4551 2800);
FORCEPROP 2 LAST CDS_LIB mstr_standard
J 0
(-3850 2800);
DISPLAY 0.787234 (-3850 2800);
PAINT MONO (-3850 2800);
DISPLAY INVISIBLE (-3850 2800);
FORCEPROP 1 LAST OFFPAGE TRUE
J 0
(-3525 2675);
DISPLAY 0.936170 (-3525 2675);
PAINT GREEN (-3525 2675);
DISPLAY INVISIBLE (-3525 2675);
FORCEPROP 1 LAST COMMENT_BODY TRUE
J 0
(-3725 2700);
DISPLAY 0.936170 (-3725 2700);
PAINT GREEN (-3725 2700);
DISPLAY INVISIBLE (-3725 2700);
FORCEPROP 2 LAST PATH I147
J 0
(-3800 2875);
DISPLAY 0.787234 (-3800 2875);
PAINT MONO (-3800 2875);
DISPLAY INVISIBLE (-3800 2875);
FORCEADD OFFPAGE..5
(-4075 2250);
FORCEPROP 2 LAST $XR0 88 
J 0
(-4299 2250);
DISPLAY 0.638298 (-4299 2250);
PAINT MONO (-4299 2250);
FORCEPROP 2 LAST $XR1 62 
J 0
(-4389 2250);
DISPLAY 0.638298 (-4389 2250);
PAINT MONO (-4389 2250);
FORCEPROP 2 LAST CDS_LIB mstr_standard
J 0
(-4075 2250);
DISPLAY 0.787234 (-4075 2250);
PAINT MONO (-4075 2250);
DISPLAY INVISIBLE (-4075 2250);
FORCEPROP 1 LAST OFFPAGE TRUE
J 0
(-3750 2125);
DISPLAY 1.404255 (-3750 2125);
PAINT GREEN (-3750 2125);
DISPLAY INVISIBLE (-3750 2125);
FORCEPROP 1 LAST COMMENT_BODY TRUE
J 0
(-3975 2175);
DISPLAY 1.404255 (-3975 2175);
PAINT GREEN (-3975 2175);
DISPLAY INVISIBLE (-3975 2175);
FORCEPROP 2 LAST PATH I148
J 0
(-4025 2325);
DISPLAY 0.787234 (-4025 2325);
PAINT MONO (-4025 2325);
DISPLAY INVISIBLE (-4025 2325);
FORCEADD OFFPAGE..1
(-4050 2200);
FORCEPROP 2 LAST $XR0 62 
J 0
(-4301 2200);
DISPLAY 0.638298 (-4301 2200);
PAINT MONO (-4301 2200);
FORCEPROP 2 LAST $XR1 88 
J 0
(-4391 2200);
DISPLAY 0.638298 (-4391 2200);
PAINT MONO (-4391 2200);
FORCEPROP 2 LAST CDS_LIB mstr_standard
J 0
(-4050 2200);
DISPLAY 0.787234 (-4050 2200);
PAINT MONO (-4050 2200);
DISPLAY INVISIBLE (-4050 2200);
FORCEPROP 1 LAST OFFPAGE TRUE
J 0
(-3725 2075);
DISPLAY 0.936170 (-3725 2075);
PAINT GREEN (-3725 2075);
DISPLAY INVISIBLE (-3725 2075);
FORCEPROP 1 LAST COMMENT_BODY TRUE
J 0
(-3925 2100);
DISPLAY 0.936170 (-3925 2100);
PAINT GREEN (-3925 2100);
DISPLAY INVISIBLE (-3925 2100);
FORCEPROP 2 LAST PATH I149
J 0
(-4000 2275);
DISPLAY 0.787234 (-4000 2275);
PAINT MONO (-4000 2275);
DISPLAY INVISIBLE (-4000 2275);
FORCEADD TAP..6
R 2
(900 4200);
FORCEPROP 3 LASTPIN (850 4200) SIG_NAME M_M_DQS_DN<8>
J 0
(860 4210);
DISPLAY 0.659574 (860 4210);
PAINT MONO (860 4210);
DISPLAY INVISIBLE (860 4210);
FORCEPROP 1 LASTPIN (850 4200) BN 8
J 2
(900 4210);
DISPLAY 0.617021 (900 4210);
PAINT PINK (900 4210);
FORCEPROP 2 LAST CDS_LIB mstr_standard
J 0
(900 4200);
DISPLAY 0.787234 (900 4200);
PAINT MONO (900 4200);
DISPLAY INVISIBLE (900 4200);
FORCEPROP 1 LAST BODY_TYPE PLUMBING
J 2
(900 4150);
DISPLAY 1.234043 (900 4150);
PAINT GREEN (900 4150);
DISPLAY INVISIBLE (900 4150);
FORCEPROP 1 LAST HDL_TAP TRUE
J 2
(575 4075);
DISPLAY 1.234043 (575 4075);
PAINT GREEN (575 4075);
DISPLAY INVISIBLE (575 4075);
FORCEPROP 1 LAST PATH I15
J 2
(900 4200);
DISPLAY 0.936170 (900 4200);
PAINT GREEN (900 4200);
DISPLAY INVISIBLE (900 4200);
FORCEADD OFFPAGE..6
(-3850 2900);
FORCEPROP 2 LAST $XR0 62 
J 0
(-4099 2900);
DISPLAY 0.638298 (-4099 2900);
PAINT MONO (-4099 2900);
FORCEPROP 2 LAST $XR1 88 
J 0
(-4189 2900);
DISPLAY 0.638298 (-4189 2900);
PAINT MONO (-4189 2900);
FORCEPROP 2 LAST CDS_LIB mstr_standard
J 0
(-3850 2900);
DISPLAY 0.787234 (-3850 2900);
PAINT MONO (-3850 2900);
DISPLAY INVISIBLE (-3850 2900);
FORCEPROP 1 LAST OFFPAGE TRUE
J 0
(-3525 2775);
DISPLAY 0.936170 (-3525 2775);
PAINT GREEN (-3525 2775);
DISPLAY INVISIBLE (-3525 2775);
FORCEPROP 1 LAST COMMENT_BODY TRUE
J 0
(-3750 2825);
DISPLAY 0.936170 (-3750 2825);
PAINT GREEN (-3750 2825);
DISPLAY INVISIBLE (-3750 2825);
FORCEPROP 2 LAST PATH I150
J 0
(-3800 2975);
DISPLAY 0.787234 (-3800 2975);
PAINT MONO (-3800 2975);
DISPLAY INVISIBLE (-3800 2975);
FORCEADD TAP..6
(-3250 3700);
FORCEPROP 3 LASTPIN (-3200 3700) SIG_NAME M_M_CLK_DP<1>
J 0
(-3190 3710);
DISPLAY 0.659574 (-3190 3710);
PAINT MONO (-3190 3710);
DISPLAY INVISIBLE (-3190 3710);
FORCEPROP 1 LASTPIN (-3200 3700) BN 1
J 0
(-3250 3710);
DISPLAY 0.617021 (-3250 3710);
PAINT PINK (-3250 3710);
FORCEPROP 2 LAST CDS_LIB mstr_standard
J 0
(-3250 3700);
DISPLAY 0.787234 (-3250 3700);
PAINT MONO (-3250 3700);
DISPLAY INVISIBLE (-3250 3700);
FORCEPROP 1 LAST BODY_TYPE PLUMBING
J 0
(-3250 3650);
DISPLAY 1.234043 (-3250 3650);
PAINT GREEN (-3250 3650);
DISPLAY INVISIBLE (-3250 3650);
FORCEPROP 1 LAST HDL_TAP TRUE
J 0
(-2925 3575);
DISPLAY 1.234043 (-2925 3575);
PAINT GREEN (-2925 3575);
DISPLAY INVISIBLE (-2925 3575);
FORCEPROP 1 LAST PATH I152
J 0
(-3250 3700);
DISPLAY 0.936170 (-3250 3700);
PAINT GREEN (-3250 3700);
DISPLAY INVISIBLE (-3250 3700);
FORCEADD TAP..6
(-3250 3600);
FORCEPROP 3 LASTPIN (-3200 3600) SIG_NAME M_M_CLK_DP<0>
J 0
(-3190 3610);
DISPLAY 0.659574 (-3190 3610);
PAINT MONO (-3190 3610);
DISPLAY INVISIBLE (-3190 3610);
FORCEPROP 1 LASTPIN (-3200 3600) BN 0
J 0
(-3250 3610);
DISPLAY 0.617021 (-3250 3610);
PAINT PINK (-3250 3610);
FORCEPROP 2 LAST CDS_LIB mstr_standard
J 0
(-3250 3600);
DISPLAY 0.787234 (-3250 3600);
PAINT MONO (-3250 3600);
DISPLAY INVISIBLE (-3250 3600);
FORCEPROP 1 LAST BODY_TYPE PLUMBING
J 0
(-3250 3550);
DISPLAY 1.234043 (-3250 3550);
PAINT GREEN (-3250 3550);
DISPLAY INVISIBLE (-3250 3550);
FORCEPROP 1 LAST HDL_TAP TRUE
J 0
(-2925 3475);
DISPLAY 1.234043 (-2925 3475);
PAINT GREEN (-2925 3475);
DISPLAY INVISIBLE (-2925 3475);
FORCEPROP 1 LAST PATH I153
J 0
(-3250 3600);
DISPLAY 0.936170 (-3250 3600);
PAINT GREEN (-3250 3600);
DISPLAY INVISIBLE (-3250 3600);
FORCEADD TAP..6
(-3450 3650);
FORCEPROP 3 LASTPIN (-3400 3650) SIG_NAME M_M_CLK_DN<1>
J 0
(-3390 3660);
DISPLAY 0.659574 (-3390 3660);
PAINT MONO (-3390 3660);
DISPLAY INVISIBLE (-3390 3660);
FORCEPROP 1 LASTPIN (-3400 3650) BN 1
J 0
(-3450 3660);
DISPLAY 0.617021 (-3450 3660);
PAINT PINK (-3450 3660);
FORCEPROP 2 LAST CDS_LIB mstr_standard
J 0
(-3450 3650);
DISPLAY 0.787234 (-3450 3650);
PAINT MONO (-3450 3650);
DISPLAY INVISIBLE (-3450 3650);
FORCEPROP 1 LAST BODY_TYPE PLUMBING
J 0
(-3450 3600);
DISPLAY 1.234043 (-3450 3600);
PAINT GREEN (-3450 3600);
DISPLAY INVISIBLE (-3450 3600);
FORCEPROP 1 LAST HDL_TAP TRUE
J 0
(-3125 3525);
DISPLAY 1.234043 (-3125 3525);
PAINT GREEN (-3125 3525);
DISPLAY INVISIBLE (-3125 3525);
FORCEPROP 1 LAST PATH I154
J 0
(-3450 3650);
DISPLAY 0.936170 (-3450 3650);
PAINT GREEN (-3450 3650);
DISPLAY INVISIBLE (-3450 3650);
FORCEADD TAP..6
(-3450 3550);
FORCEPROP 3 LASTPIN (-3400 3550) SIG_NAME M_M_CLK_DN<0>
J 0
(-3390 3560);
DISPLAY 0.659574 (-3390 3560);
PAINT MONO (-3390 3560);
DISPLAY INVISIBLE (-3390 3560);
FORCEPROP 1 LASTPIN (-3400 3550) BN 0
J 0
(-3450 3560);
DISPLAY 0.617021 (-3450 3560);
PAINT PINK (-3450 3560);
FORCEPROP 2 LAST CDS_LIB mstr_standard
J 0
(-3450 3550);
DISPLAY 0.787234 (-3450 3550);
PAINT MONO (-3450 3550);
DISPLAY INVISIBLE (-3450 3550);
FORCEPROP 1 LAST BODY_TYPE PLUMBING
J 0
(-3450 3500);
DISPLAY 1.234043 (-3450 3500);
PAINT GREEN (-3450 3500);
DISPLAY INVISIBLE (-3450 3500);
FORCEPROP 1 LAST HDL_TAP TRUE
J 0
(-3125 3425);
DISPLAY 1.234043 (-3125 3425);
PAINT GREEN (-3125 3425);
DISPLAY INVISIBLE (-3125 3425);
FORCEPROP 1 LAST PATH I155
J 0
(-3450 3550);
DISPLAY 0.936170 (-3450 3550);
PAINT GREEN (-3450 3550);
DISPLAY INVISIBLE (-3450 3550);
FORCEADD OFFPAGE..1
(-3850 3725);
FORCEPROP 2 LAST $XR0 62 
J 0
(-4101 3725);
DISPLAY 0.638298 (-4101 3725);
PAINT MONO (-4101 3725);
FORCEPROP 2 LAST $XR1 88 
J 0
(-4191 3725);
DISPLAY 0.638298 (-4191 3725);
PAINT MONO (-4191 3725);
FORCEPROP 2 LAST CDS_LIB mstr_standard
J 0
(-3850 3725);
DISPLAY 0.787234 (-3850 3725);
PAINT MONO (-3850 3725);
DISPLAY INVISIBLE (-3850 3725);
FORCEPROP 1 LAST OFFPAGE TRUE
J 0
(-3525 3600);
DISPLAY 0.936170 (-3525 3600);
PAINT GREEN (-3525 3600);
DISPLAY INVISIBLE (-3525 3600);
FORCEPROP 1 LAST COMMENT_BODY TRUE
J 0
(-3725 3625);
DISPLAY 0.936170 (-3725 3625);
PAINT GREEN (-3725 3625);
DISPLAY INVISIBLE (-3725 3625);
FORCEPROP 2 LAST PATH I156
J 0
(-3800 3800);
DISPLAY 0.787234 (-3800 3800);
PAINT MONO (-3800 3800);
DISPLAY INVISIBLE (-3800 3800);
FORCEADD OFFPAGE..1
(-3850 3775);
FORCEPROP 2 LAST $XR0 62 
J 0
(-4101 3775);
DISPLAY 0.638298 (-4101 3775);
PAINT MONO (-4101 3775);
FORCEPROP 2 LAST $XR1 88 
J 0
(-4191 3775);
DISPLAY 0.638298 (-4191 3775);
PAINT MONO (-4191 3775);
FORCEPROP 2 LAST CDS_LIB mstr_standard
J 0
(-3850 3775);
DISPLAY 0.787234 (-3850 3775);
PAINT MONO (-3850 3775);
DISPLAY INVISIBLE (-3850 3775);
FORCEPROP 1 LAST OFFPAGE TRUE
J 0
(-3525 3650);
DISPLAY 0.936170 (-3525 3650);
PAINT GREEN (-3525 3650);
DISPLAY INVISIBLE (-3525 3650);
FORCEPROP 1 LAST COMMENT_BODY TRUE
J 0
(-3725 3675);
DISPLAY 0.936170 (-3725 3675);
PAINT GREEN (-3725 3675);
DISPLAY INVISIBLE (-3725 3675);
FORCEPROP 2 LAST PATH I157
J 0
(-3800 3850);
DISPLAY 0.787234 (-3800 3850);
PAINT MONO (-3800 3850);
DISPLAY INVISIBLE (-3800 3850);
FORCEADD TAP..6
(-3250 3400);
FORCEPROP 3 LASTPIN (-3200 3400) SIG_NAME M_M_CS_N<3>
J 0
(-3190 3410);
DISPLAY 0.659574 (-3190 3410);
PAINT MONO (-3190 3410);
DISPLAY INVISIBLE (-3190 3410);
FORCEPROP 1 LASTPIN (-3200 3400) BN 3
J 0
(-3250 3410);
DISPLAY 0.617021 (-3250 3410);
PAINT PINK (-3250 3410);
FORCEPROP 2 LAST CDS_LIB mstr_standard
J 0
(-3250 3400);
DISPLAY 0.787234 (-3250 3400);
PAINT MONO (-3250 3400);
DISPLAY INVISIBLE (-3250 3400);
FORCEPROP 1 LAST BODY_TYPE PLUMBING
J 0
(-3250 3350);
DISPLAY 1.234043 (-3250 3350);
PAINT GREEN (-3250 3350);
DISPLAY INVISIBLE (-3250 3350);
FORCEPROP 1 LAST HDL_TAP TRUE
J 0
(-2925 3275);
DISPLAY 1.234043 (-2925 3275);
PAINT GREEN (-2925 3275);
DISPLAY INVISIBLE (-2925 3275);
FORCEPROP 1 LAST PATH I158
J 0
(-3250 3400);
DISPLAY 0.936170 (-3250 3400);
PAINT GREEN (-3250 3400);
DISPLAY INVISIBLE (-3250 3400);
FORCEADD TAP..6
(-3250 3350);
FORCEPROP 3 LASTPIN (-3200 3350) SIG_NAME M_M_CS_N<2>
J 0
(-3190 3360);
DISPLAY 0.659574 (-3190 3360);
PAINT MONO (-3190 3360);
DISPLAY INVISIBLE (-3190 3360);
FORCEPROP 1 LASTPIN (-3200 3350) BN 2
J 0
(-3250 3360);
DISPLAY 0.617021 (-3250 3360);
PAINT PINK (-3250 3360);
FORCEPROP 2 LAST CDS_LIB mstr_standard
J 0
(-3250 3350);
DISPLAY 0.787234 (-3250 3350);
PAINT MONO (-3250 3350);
DISPLAY INVISIBLE (-3250 3350);
FORCEPROP 1 LAST BODY_TYPE PLUMBING
J 0
(-3250 3300);
DISPLAY 1.234043 (-3250 3300);
PAINT GREEN (-3250 3300);
DISPLAY INVISIBLE (-3250 3300);
FORCEPROP 1 LAST HDL_TAP TRUE
J 0
(-2925 3225);
DISPLAY 1.234043 (-2925 3225);
PAINT GREEN (-2925 3225);
DISPLAY INVISIBLE (-2925 3225);
FORCEPROP 1 LAST PATH I159
J 0
(-3250 3350);
DISPLAY 0.936170 (-3250 3350);
PAINT GREEN (-3250 3350);
DISPLAY INVISIBLE (-3250 3350);
FORCEADD TAP..6
R 2
(900 4100);
FORCEPROP 3 LASTPIN (850 4100) SIG_NAME M_M_DQS_DN<7>
J 0
(860 4110);
DISPLAY 0.659574 (860 4110);
PAINT MONO (860 4110);
DISPLAY INVISIBLE (860 4110);
FORCEPROP 1 LASTPIN (850 4100) BN 7
J 2
(900 4110);
DISPLAY 0.617021 (900 4110);
PAINT PINK (900 4110);
FORCEPROP 2 LAST CDS_LIB mstr_standard
J 0
(900 4100);
DISPLAY 0.787234 (900 4100);
PAINT MONO (900 4100);
DISPLAY INVISIBLE (900 4100);
FORCEPROP 1 LAST BODY_TYPE PLUMBING
J 2
(900 4050);
DISPLAY 1.234043 (900 4050);
PAINT GREEN (900 4050);
DISPLAY INVISIBLE (900 4050);
FORCEPROP 1 LAST HDL_TAP TRUE
J 2
(575 3975);
DISPLAY 1.234043 (575 3975);
PAINT GREEN (575 3975);
DISPLAY INVISIBLE (575 3975);
FORCEPROP 1 LAST PATH I16
J 2
(900 4100);
DISPLAY 0.936170 (900 4100);
PAINT GREEN (900 4100);
DISPLAY INVISIBLE (900 4100);
FORCEADD TAP..6
(-3250 3300);
FORCEPROP 3 LASTPIN (-3200 3300) SIG_NAME M_M_CS_N<1>
J 0
(-3190 3310);
DISPLAY 0.659574 (-3190 3310);
PAINT MONO (-3190 3310);
DISPLAY INVISIBLE (-3190 3310);
FORCEPROP 1 LASTPIN (-3200 3300) BN 1
J 0
(-3250 3310);
DISPLAY 0.617021 (-3250 3310);
PAINT PINK (-3250 3310);
FORCEPROP 2 LAST CDS_LIB mstr_standard
J 0
(-3250 3300);
DISPLAY 0.787234 (-3250 3300);
PAINT MONO (-3250 3300);
DISPLAY INVISIBLE (-3250 3300);
FORCEPROP 1 LAST BODY_TYPE PLUMBING
J 0
(-3250 3250);
DISPLAY 1.234043 (-3250 3250);
PAINT GREEN (-3250 3250);
DISPLAY INVISIBLE (-3250 3250);
FORCEPROP 1 LAST HDL_TAP TRUE
J 0
(-2925 3175);
DISPLAY 1.234043 (-2925 3175);
PAINT GREEN (-2925 3175);
DISPLAY INVISIBLE (-2925 3175);
FORCEPROP 1 LAST PATH I160
J 0
(-3250 3300);
DISPLAY 0.936170 (-3250 3300);
PAINT GREEN (-3250 3300);
DISPLAY INVISIBLE (-3250 3300);
FORCEADD TAP..6
(-3250 3250);
FORCEPROP 3 LASTPIN (-3200 3250) SIG_NAME M_M_CS_N<0>
J 0
(-3190 3260);
DISPLAY 0.659574 (-3190 3260);
PAINT MONO (-3190 3260);
DISPLAY INVISIBLE (-3190 3260);
FORCEPROP 1 LASTPIN (-3200 3250) BN 0
J 0
(-3250 3260);
DISPLAY 0.617021 (-3250 3260);
PAINT PINK (-3250 3260);
FORCEPROP 2 LAST CDS_LIB mstr_standard
J 0
(-3250 3250);
DISPLAY 0.787234 (-3250 3250);
PAINT MONO (-3250 3250);
DISPLAY INVISIBLE (-3250 3250);
FORCEPROP 1 LAST BODY_TYPE PLUMBING
J 0
(-3250 3200);
DISPLAY 1.234043 (-3250 3200);
PAINT GREEN (-3250 3200);
DISPLAY INVISIBLE (-3250 3200);
FORCEPROP 1 LAST HDL_TAP TRUE
J 0
(-2925 3125);
DISPLAY 1.234043 (-2925 3125);
PAINT GREEN (-2925 3125);
DISPLAY INVISIBLE (-2925 3125);
FORCEPROP 1 LAST PATH I161
J 0
(-3250 3250);
DISPLAY 0.936170 (-3250 3250);
PAINT GREEN (-3250 3250);
DISPLAY INVISIBLE (-3250 3250);
FORCEADD OFFPAGE..1
(-3850 3450);
FORCEPROP 2 LAST $XR0 62 
J 0
(-4101 3450);
DISPLAY 0.638298 (-4101 3450);
PAINT MONO (-4101 3450);
FORCEPROP 2 LAST $XR1 88 
J 0
(-4191 3450);
DISPLAY 0.638298 (-4191 3450);
PAINT MONO (-4191 3450);
FORCEPROP 2 LAST CDS_LIB mstr_standard
J 0
(-3850 3450);
DISPLAY 0.787234 (-3850 3450);
PAINT MONO (-3850 3450);
DISPLAY INVISIBLE (-3850 3450);
FORCEPROP 1 LAST OFFPAGE TRUE
J 0
(-3525 3325);
DISPLAY 0.936170 (-3525 3325);
PAINT GREEN (-3525 3325);
DISPLAY INVISIBLE (-3525 3325);
FORCEPROP 1 LAST COMMENT_BODY TRUE
J 0
(-3725 3350);
DISPLAY 0.936170 (-3725 3350);
PAINT GREEN (-3725 3350);
DISPLAY INVISIBLE (-3725 3350);
FORCEPROP 2 LAST PATH I162
J 0
(-3800 3525);
DISPLAY 0.787234 (-3800 3525);
PAINT MONO (-3800 3525);
DISPLAY INVISIBLE (-3800 3525);
FORCEADD TAP..6
(-3250 3150);
FORCEPROP 3 LASTPIN (-3200 3150) SIG_NAME M_M_CKE<1>
J 0
(-3190 3160);
DISPLAY 0.659574 (-3190 3160);
PAINT MONO (-3190 3160);
DISPLAY INVISIBLE (-3190 3160);
FORCEPROP 1 LASTPIN (-3200 3150) BN 1
J 0
(-3250 3160);
DISPLAY 0.617021 (-3250 3160);
PAINT PINK (-3250 3160);
FORCEPROP 2 LAST CDS_LIB mstr_standard
J 0
(-3250 3150);
DISPLAY 0.787234 (-3250 3150);
PAINT MONO (-3250 3150);
DISPLAY INVISIBLE (-3250 3150);
FORCEPROP 1 LAST BODY_TYPE PLUMBING
J 0
(-3250 3100);
DISPLAY 1.234043 (-3250 3100);
PAINT GREEN (-3250 3100);
DISPLAY INVISIBLE (-3250 3100);
FORCEPROP 1 LAST HDL_TAP TRUE
J 0
(-2925 3025);
DISPLAY 1.234043 (-2925 3025);
PAINT GREEN (-2925 3025);
DISPLAY INVISIBLE (-2925 3025);
FORCEPROP 1 LAST PATH I163
J 0
(-3250 3150);
DISPLAY 0.936170 (-3250 3150);
PAINT GREEN (-3250 3150);
DISPLAY INVISIBLE (-3250 3150);
FORCEADD TAP..6
(-3250 3100);
FORCEPROP 3 LASTPIN (-3200 3100) SIG_NAME M_M_CKE<0>
J 0
(-3190 3110);
DISPLAY 0.659574 (-3190 3110);
PAINT MONO (-3190 3110);
DISPLAY INVISIBLE (-3190 3110);
FORCEPROP 1 LASTPIN (-3200 3100) BN 0
J 0
(-3250 3110);
DISPLAY 0.617021 (-3250 3110);
PAINT PINK (-3250 3110);
FORCEPROP 2 LAST CDS_LIB mstr_standard
J 0
(-3250 3100);
DISPLAY 0.787234 (-3250 3100);
PAINT MONO (-3250 3100);
DISPLAY INVISIBLE (-3250 3100);
FORCEPROP 1 LAST BODY_TYPE PLUMBING
J 0
(-3250 3050);
DISPLAY 1.234043 (-3250 3050);
PAINT GREEN (-3250 3050);
DISPLAY INVISIBLE (-3250 3050);
FORCEPROP 1 LAST HDL_TAP TRUE
J 0
(-2925 2975);
DISPLAY 1.234043 (-2925 2975);
PAINT GREEN (-2925 2975);
DISPLAY INVISIBLE (-2925 2975);
FORCEPROP 1 LAST PATH I164
J 0
(-3250 3100);
DISPLAY 0.936170 (-3250 3100);
PAINT GREEN (-3250 3100);
DISPLAY INVISIBLE (-3250 3100);
FORCEADD TAP..6
(-3250 3000);
FORCEPROP 3 LASTPIN (-3200 3000) SIG_NAME M_M_ODT<1>
J 0
(-3190 3010);
DISPLAY 0.659574 (-3190 3010);
PAINT MONO (-3190 3010);
DISPLAY INVISIBLE (-3190 3010);
FORCEPROP 1 LASTPIN (-3200 3000) BN 1
J 0
(-3250 3010);
DISPLAY 0.617021 (-3250 3010);
PAINT PINK (-3250 3010);
FORCEPROP 2 LAST CDS_LIB mstr_standard
J 0
(-3250 3000);
DISPLAY 0.787234 (-3250 3000);
PAINT MONO (-3250 3000);
DISPLAY INVISIBLE (-3250 3000);
FORCEPROP 1 LAST BODY_TYPE PLUMBING
J 0
(-3250 2950);
DISPLAY 1.234043 (-3250 2950);
PAINT GREEN (-3250 2950);
DISPLAY INVISIBLE (-3250 2950);
FORCEPROP 1 LAST HDL_TAP TRUE
J 0
(-2925 2875);
DISPLAY 1.234043 (-2925 2875);
PAINT GREEN (-2925 2875);
DISPLAY INVISIBLE (-2925 2875);
FORCEPROP 1 LAST PATH I165
J 0
(-3250 3000);
DISPLAY 0.936170 (-3250 3000);
PAINT GREEN (-3250 3000);
DISPLAY INVISIBLE (-3250 3000);
FORCEADD TAP..6
(-3250 2950);
FORCEPROP 3 LASTPIN (-3200 2950) SIG_NAME M_M_ODT<0>
J 0
(-3190 2960);
DISPLAY 0.659574 (-3190 2960);
PAINT MONO (-3190 2960);
DISPLAY INVISIBLE (-3190 2960);
FORCEPROP 1 LASTPIN (-3200 2950) BN 0
J 0
(-3250 2960);
DISPLAY 0.617021 (-3250 2960);
PAINT PINK (-3250 2960);
FORCEPROP 2 LAST CDS_LIB mstr_standard
J 0
(-3250 2950);
DISPLAY 0.787234 (-3250 2950);
PAINT MONO (-3250 2950);
DISPLAY INVISIBLE (-3250 2950);
FORCEPROP 1 LAST BODY_TYPE PLUMBING
J 0
(-3250 2900);
DISPLAY 1.234043 (-3250 2900);
PAINT GREEN (-3250 2900);
DISPLAY INVISIBLE (-3250 2900);
FORCEPROP 1 LAST HDL_TAP TRUE
J 0
(-2925 2825);
DISPLAY 1.234043 (-2925 2825);
PAINT GREEN (-2925 2825);
DISPLAY INVISIBLE (-2925 2825);
FORCEPROP 1 LAST PATH I166
J 0
(-3250 2950);
DISPLAY 0.936170 (-3250 2950);
PAINT GREEN (-3250 2950);
DISPLAY INVISIBLE (-3250 2950);
FORCEADD OFFPAGE..1
(-3850 3100);
FORCEPROP 2 LAST $XR0 62 
J 0
(-4101 3100);
DISPLAY 0.638298 (-4101 3100);
PAINT MONO (-4101 3100);
FORCEPROP 2 LAST $XR1 88 
J 0
(-4191 3100);
DISPLAY 0.638298 (-4191 3100);
PAINT MONO (-4191 3100);
FORCEPROP 2 LAST CDS_LIB mstr_standard
J 0
(-3850 3100);
DISPLAY 0.787234 (-3850 3100);
PAINT MONO (-3850 3100);
DISPLAY INVISIBLE (-3850 3100);
FORCEPROP 1 LAST OFFPAGE TRUE
J 0
(-3525 2975);
DISPLAY 0.936170 (-3525 2975);
PAINT GREEN (-3525 2975);
DISPLAY INVISIBLE (-3525 2975);
FORCEPROP 1 LAST COMMENT_BODY TRUE
J 0
(-3725 3000);
DISPLAY 0.936170 (-3725 3000);
PAINT GREEN (-3725 3000);
DISPLAY INVISIBLE (-3725 3000);
FORCEPROP 2 LAST PATH I167
J 0
(-3800 3175);
DISPLAY 0.787234 (-3800 3175);
PAINT MONO (-3800 3175);
DISPLAY INVISIBLE (-3800 3175);
FORCEADD OFFPAGE..1
(-3850 3225);
FORCEPROP 2 LAST $XR0 62 
J 0
(-4101 3225);
DISPLAY 0.638298 (-4101 3225);
PAINT MONO (-4101 3225);
FORCEPROP 2 LAST $XR1 88 
J 0
(-4191 3225);
DISPLAY 0.638298 (-4191 3225);
PAINT MONO (-4191 3225);
FORCEPROP 2 LAST CDS_LIB mstr_standard
J 0
(-3850 3225);
DISPLAY 0.787234 (-3850 3225);
PAINT MONO (-3850 3225);
DISPLAY INVISIBLE (-3850 3225);
FORCEPROP 1 LAST OFFPAGE TRUE
J 0
(-3525 3100);
DISPLAY 0.936170 (-3525 3100);
PAINT GREEN (-3525 3100);
DISPLAY INVISIBLE (-3525 3100);
FORCEPROP 1 LAST COMMENT_BODY TRUE
J 0
(-3725 3125);
DISPLAY 0.936170 (-3725 3125);
PAINT GREEN (-3725 3125);
DISPLAY INVISIBLE (-3725 3125);
FORCEPROP 2 LAST PATH I168
J 0
(-3800 3300);
DISPLAY 0.787234 (-3800 3300);
PAINT MONO (-3800 3300);
DISPLAY INVISIBLE (-3800 3300);
FORCEADD SCONN288_H44441004..4
(-400 2050);
FORCEPROP 1 LAST LOCATION J1A1
J 0
(-850 3150);
DISPLAY 0.617021 (-850 3150);
PAINT AQUA (-850 3150);
FORCEPROP 1 LAST PART_NUMBER H44441-004
J 0
(-850 1000);
DISPLAY 0.617021 (-850 1000);
PAINT BLUE (-850 1000);
FORCEPROP 1 LAST MATERIAL SCONN
J 0
(-850 3100);
DISPLAY 0.617021 (-850 3100);
PAINT SKYBLUE (-850 3100);
FORCEPROP 2 LASTPIN (-900 2600) $PN 77
J 2
(-910 2610);
DISPLAY 0.617021 (-910 2610);
PAINT ORANGE (-910 2610);
FORCEPROP 2 LASTPIN (-900 2550) $PN 221
J 2
(-910 2560);
DISPLAY 0.617021 (-910 2560);
PAINT ORANGE (-910 2560);
FORCEPROP 2 LASTPIN (-900 2900) $PN 142
J 2
(-910 2910);
DISPLAY 0.617021 (-910 2910);
PAINT ORANGE (-910 2910);
FORCEPROP 2 LASTPIN (-900 2850) $PN 143
J 2
(-910 2860);
DISPLAY 0.617021 (-910 2860);
PAINT ORANGE (-910 2860);
FORCEPROP 2 LASTPIN (-900 2800) $PN 288
J 2
(-910 2810);
DISPLAY 0.617021 (-910 2810);
PAINT ORANGE (-910 2810);
FORCEPROP 2 LASTPIN (-900 2750) $PN 286
J 2
(-910 2760);
DISPLAY 0.617021 (-910 2760);
PAINT ORANGE (-910 2760);
FORCEPROP 2 LASTPIN (-900 2700) $PN 287
J 2
(-910 2710);
DISPLAY 0.617021 (-910 2710);
PAINT ORANGE (-910 2710);
FORCEPROP 2 LASTPIN (-900 2450) $PN 59
J 2
(-910 2460);
DISPLAY 0.617021 (-910 2460);
PAINT ORANGE (-910 2460);
FORCEPROP 2 LASTPIN (-900 2400) $PN 61
J 2
(-910 2410);
DISPLAY 0.617021 (-910 2410);
PAINT ORANGE (-910 2410);
FORCEPROP 2 LASTPIN (-900 2350) $PN 64
J 2
(-910 2360);
DISPLAY 0.617021 (-910 2360);
PAINT ORANGE (-910 2360);
FORCEPROP 2 LASTPIN (-900 2300) $PN 67
J 2
(-910 2310);
DISPLAY 0.617021 (-910 2310);
PAINT ORANGE (-910 2310);
FORCEPROP 2 LASTPIN (-900 2250) $PN 70
J 2
(-910 2260);
DISPLAY 0.617021 (-910 2260);
PAINT ORANGE (-910 2260);
FORCEPROP 2 LASTPIN (-900 2200) $PN 73
J 2
(-910 2210);
DISPLAY 0.617021 (-910 2210);
PAINT ORANGE (-910 2210);
FORCEPROP 2 LASTPIN (-900 2150) $PN 76
J 2
(-910 2160);
DISPLAY 0.617021 (-910 2160);
PAINT ORANGE (-910 2160);
FORCEPROP 2 LASTPIN (-900 2100) $PN 80
J 2
(-910 2110);
DISPLAY 0.617021 (-910 2110);
PAINT ORANGE (-910 2110);
FORCEPROP 2 LASTPIN (-900 2050) $PN 83
J 2
(-910 2060);
DISPLAY 0.617021 (-910 2060);
PAINT ORANGE (-910 2060);
FORCEPROP 2 LASTPIN (-900 2000) $PN 85
J 2
(-910 2010);
DISPLAY 0.617021 (-910 2010);
PAINT ORANGE (-910 2010);
FORCEPROP 2 LASTPIN (-900 1950) $PN 88
J 2
(-910 1960);
DISPLAY 0.617021 (-910 1960);
PAINT ORANGE (-910 1960);
FORCEPROP 2 LASTPIN (-900 1900) $PN 90
J 2
(-910 1910);
DISPLAY 0.617021 (-910 1910);
PAINT ORANGE (-910 1910);
FORCEPROP 2 LASTPIN (-900 1850) $PN 92
J 2
(-910 1860);
DISPLAY 0.617021 (-910 1860);
PAINT ORANGE (-910 1860);
FORCEPROP 2 LASTPIN (-900 1800) $PN 204
J 2
(-910 1810);
DISPLAY 0.617021 (-910 1810);
PAINT ORANGE (-910 1810);
FORCEPROP 2 LASTPIN (-900 1750) $PN 206
J 2
(-910 1760);
DISPLAY 0.617021 (-910 1760);
PAINT ORANGE (-910 1760);
FORCEPROP 2 LASTPIN (-900 1700) $PN 209
J 2
(-910 1710);
DISPLAY 0.617021 (-910 1710);
PAINT ORANGE (-910 1710);
FORCEPROP 2 LASTPIN (-900 1650) $PN 212
J 2
(-910 1660);
DISPLAY 0.617021 (-910 1660);
PAINT ORANGE (-910 1660);
FORCEPROP 2 LASTPIN (-900 1600) $PN 215
J 2
(-910 1610);
DISPLAY 0.617021 (-910 1610);
PAINT ORANGE (-910 1610);
FORCEPROP 2 LASTPIN (-900 1550) $PN 217
J 2
(-910 1560);
DISPLAY 0.617021 (-910 1560);
PAINT ORANGE (-910 1560);
FORCEPROP 2 LASTPIN (-900 1500) $PN 220
J 2
(-910 1510);
DISPLAY 0.617021 (-910 1510);
PAINT ORANGE (-910 1510);
FORCEPROP 2 LASTPIN (-900 1450) $PN 223
J 2
(-910 1460);
DISPLAY 0.617021 (-910 1460);
PAINT ORANGE (-910 1460);
FORCEPROP 2 LASTPIN (-900 1400) $PN 226
J 2
(-910 1410);
DISPLAY 0.617021 (-910 1410);
PAINT ORANGE (-910 1410);
FORCEPROP 2 LASTPIN (-900 1350) $PN 229
J 2
(-910 1360);
DISPLAY 0.617021 (-910 1360);
PAINT ORANGE (-910 1360);
FORCEPROP 2 LASTPIN (-900 1300) $PN 231
J 2
(-910 1310);
DISPLAY 0.617021 (-910 1310);
PAINT ORANGE (-910 1310);
FORCEPROP 2 LASTPIN (-900 1250) $PN 233
J 2
(-910 1260);
DISPLAY 0.617021 (-910 1260);
PAINT ORANGE (-910 1260);
FORCEPROP 2 LASTPIN (-900 1200) $PN 236
J 2
(-910 1210);
DISPLAY 0.617021 (-910 1210);
PAINT ORANGE (-910 1210);
FORCEPROP 2 LASTPIN (100 2900) $PN 1
J 0
(110 2910);
DISPLAY 0.617021 (110 2910);
PAINT ORANGE (110 2910);
FORCEPROP 2 LASTPIN (100 2850) $PN 145
J 0
(110 2860);
DISPLAY 0.617021 (110 2860);
PAINT ORANGE (110 2860);
FORCEPROP 1 LAST PACK_TYPE PIP
J 0
(-850 3200);
PAINT SKYBLUE (-850 3200);
DISPLAY INVISIBLE (-850 3200);
FORCEPROP 2 LAST BOM_COST MEM
J 0
(-400 2050);
PAINT ORANGE (-400 2050);
DISPLAY INVISIBLE (-400 2050);
FORCEPROP 2 LAST CDS_LIB mstr_sconn
J 0
(-400 2050);
PAINT ORANGE (-400 2050);
DISPLAY INVISIBLE (-400 2050);
FORCEPROP 2 LAST SEC_TYPE PIP
J 0
(-850 3200);
DISPLAY 1.021277 (-850 3200);
PAINT ORANGE (-850 3200);
DISPLAY INVISIBLE (-850 3200);
FORCEPROP 2 LAST SEC 4
J 0
(-850 3200);
DISPLAY 0.680851 (-850 3200);
PAINT MONO (-850 3200);
DISPLAY INVISIBLE (-850 3200);
FORCEPROP 2 LAST CDS_LOCATION J1A1
J 0
(-850 3150);
DISPLAY 0.617021 (-850 3150);
PAINT AQUA (-850 3150);
DISPLAY INVISIBLE (-850 3150);
FORCEPROP 1 LAST PATH I169
J 0
(-400 3100);
PAINT GREEN (-400 3100);
DISPLAY INVISIBLE (-400 3100);
FORCEPROP 2 LAST ROOM DDR4_CH_M
J 0
(-400 2050);
PAINT ORANGE (-400 2050);
DISPLAY INVISIBLE (-400 2050);
FORCEADD TAP..6
R 2
(900 4000);
FORCEPROP 3 LASTPIN (850 4000) SIG_NAME M_M_DQS_DN<6>
J 0
(860 4010);
DISPLAY 0.659574 (860 4010);
PAINT MONO (860 4010);
DISPLAY INVISIBLE (860 4010);
FORCEPROP 1 LASTPIN (850 4000) BN 6
J 2
(900 4010);
DISPLAY 0.617021 (900 4010);
PAINT PINK (900 4010);
FORCEPROP 2 LAST CDS_LIB mstr_standard
J 0
(900 4000);
DISPLAY 0.787234 (900 4000);
PAINT MONO (900 4000);
DISPLAY INVISIBLE (900 4000);
FORCEPROP 1 LAST BODY_TYPE PLUMBING
J 2
(900 3950);
DISPLAY 1.234043 (900 3950);
PAINT GREEN (900 3950);
DISPLAY INVISIBLE (900 3950);
FORCEPROP 1 LAST HDL_TAP TRUE
J 2
(575 3875);
DISPLAY 1.234043 (575 3875);
PAINT GREEN (575 3875);
DISPLAY INVISIBLE (575 3875);
FORCEPROP 1 LAST PATH I17
J 2
(900 4000);
DISPLAY 0.936170 (900 4000);
PAINT GREEN (900 4000);
DISPLAY INVISIBLE (900 4000);
FORCEADD GND..1
R 2
(2500 1150);
FORCEPROP 3 LASTPIN (2500 1200) SIG_NAME GND\g
J 0
(2510 1210);
DISPLAY 0.659574 (2510 1210);
PAINT MONO (2510 1210);
DISPLAY INVISIBLE (2510 1210);
FORCEPROP 1 LAST VOLTAGE 0
J 0
(2500 1150);
PAINT SKYBLUE (2500 1150);
DISPLAY INVISIBLE (2500 1150);
FORCEPROP 2 LAST BOM_COST MEM
J 0
(2500 1155);
PAINT ORANGE (2500 1155);
DISPLAY INVISIBLE (2500 1155);
FORCEPROP 2 LAST CDS_LIB mstr_symbols
J 0
(2500 1150);
DISPLAY 0.787234 (2500 1150);
PAINT MONO (2500 1150);
DISPLAY INVISIBLE (2500 1150);
FORCEPROP 1 LAST SIZE 1B
J 2
(2425 1100);
DISPLAY 1.170213 (2425 1100);
PAINT GREEN (2425 1100);
DISPLAY INVISIBLE (2425 1100);
FORCEPROP 1 LAST BODY_TYPE PLUMBING
J 2
(2545 1107);
DISPLAY 0.340426 (2545 1107);
PAINT GREEN (2545 1107);
DISPLAY INVISIBLE (2545 1107);
FORCEPROP 1 LAST PATH I170
J 2
(2425 1150);
DISPLAY 1.404255 (2425 1150);
PAINT GREEN (2425 1150);
DISPLAY INVISIBLE (2425 1150);
FORCEPROP 2 LAST ROOM DDR4_CH_D
J 0
(2500 1155);
PAINT ORANGE (2500 1155);
DISPLAY INVISIBLE (2500 1155);
FORCEPROP 1 LAST HDL_POWER GND
J 2
(2500 1300);
DISPLAY 0.553191 (2500 1300);
PAINT GREEN (2500 1300);
DISPLAY INVISIBLE (2500 1300);
FORCEADD OFFPAGE..5
(-4225 2600);
FORCEPROP 2 LAST $XR0 43 
J 0
(-4449 2600);
DISPLAY 0.638298 (-4449 2600);
PAINT MONO (-4449 2600);
FORCEPROP 2 LAST $XR1 44 
J 0
(-4539 2600);
DISPLAY 0.638298 (-4539 2600);
PAINT MONO (-4539 2600);
FORCEPROP 2 LAST $XR2 45 
J 0
(-4629 2600);
DISPLAY 0.638298 (-4629 2600);
PAINT MONO (-4629 2600);
FORCEPROP 2 LAST $XR3 46 
J 0
(-4719 2600);
DISPLAY 0.638298 (-4719 2600);
PAINT MONO (-4719 2600);
FORCEPROP 2 LAST $XR4 47 
J 0
(-4809 2600);
DISPLAY 0.638298 (-4809 2600);
PAINT MONO (-4809 2600);
FORCEPROP 2 LAST $XR5 48 
J 0
(-4899 2600);
DISPLAY 0.638298 (-4899 2600);
PAINT MONO (-4899 2600);
FORCEPROP 2 LAST $XR6 49 
J 0
(-4989 2600);
DISPLAY 0.638298 (-4989 2600);
PAINT MONO (-4989 2600);
FORCEPROP 2 LAST $XR7 50 
J 0
(-5079 2600);
DISPLAY 0.638298 (-5079 2600);
PAINT MONO (-5079 2600);
FORCEPROP 2 LAST $XR8 51 
J 0
(-5169 2600);
DISPLAY 0.638298 (-5169 2600);
PAINT MONO (-5169 2600);
FORCEPROP 2 LAST $XR9 52 
J 0
(-5259 2600);
DISPLAY 0.638298 (-5259 2600);
PAINT MONO (-5259 2600);
FORCEPROP 2 LAST $XR10 53 
J 0
(-4449 2564);
DISPLAY 0.638298 (-4449 2564);
PAINT MONO (-4449 2564);
FORCEPROP 2 LAST $XR11 54 
J 0
(-4539 2564);
DISPLAY 0.638298 (-4539 2564);
PAINT MONO (-4539 2564);
FORCEPROP 2 LAST $XR12 77 
J 0
(-4629 2564);
DISPLAY 0.638298 (-4629 2564);
PAINT MONO (-4629 2564);
FORCEPROP 2 LAST $XR13 78 
J 0
(-4719 2564);
DISPLAY 0.638298 (-4719 2564);
PAINT MONO (-4719 2564);
FORCEPROP 2 LAST $XR14 79 
J 0
(-4809 2564);
DISPLAY 0.638298 (-4809 2564);
PAINT MONO (-4809 2564);
FORCEPROP 2 LAST $XR15 80 
J 0
(-4899 2564);
DISPLAY 0.638298 (-4899 2564);
PAINT MONO (-4899 2564);
FORCEPROP 2 LAST $XR16 81 
J 0
(-4989 2564);
DISPLAY 0.638298 (-4989 2564);
PAINT MONO (-4989 2564);
FORCEPROP 2 LAST $XR17 82 
J 0
(-5079 2564);
DISPLAY 0.638298 (-5079 2564);
PAINT MONO (-5079 2564);
FORCEPROP 2 LAST $XR18 83 
J 0
(-5169 2564);
DISPLAY 0.638298 (-5169 2564);
PAINT MONO (-5169 2564);
FORCEPROP 2 LAST $XR19 84 
J 0
(-5259 2564);
DISPLAY 0.638298 (-5259 2564);
PAINT MONO (-5259 2564);
FORCEPROP 2 LAST $XR20 85 
J 0
(-4449 2636);
DISPLAY 0.638298 (-4449 2636);
PAINT MONO (-4449 2636);
FORCEPROP 2 LAST $XR21 86 
J 0
(-4539 2636);
DISPLAY 0.638298 (-4539 2636);
PAINT MONO (-4539 2636);
FORCEPROP 2 LAST $XR22 88 
J 0
(-4629 2636);
DISPLAY 0.638298 (-4629 2636);
PAINT MONO (-4629 2636);
FORCEPROP 2 LAST $XR23 94 
J 0
(-4719 2636);
DISPLAY 0.638298 (-4719 2636);
PAINT MONO (-4719 2636);
FORCEPROP 2 LAST CDS_LIB mstr_standard
J 0
(-4225 2600);
DISPLAY 0.787234 (-4225 2600);
PAINT MONO (-4225 2600);
DISPLAY INVISIBLE (-4225 2600);
FORCEPROP 1 LAST OFFPAGE TRUE
J 0
(-3900 2475);
DISPLAY 1.404255 (-3900 2475);
PAINT GREEN (-3900 2475);
DISPLAY INVISIBLE (-3900 2475);
FORCEPROP 1 LAST COMMENT_BODY TRUE
J 0
(-4125 2525);
DISPLAY 1.404255 (-4125 2525);
PAINT GREEN (-4125 2525);
DISPLAY INVISIBLE (-4125 2525);
FORCEPROP 2 LAST PATH I171
J 0
(-4175 2675);
DISPLAY 0.787234 (-4175 2675);
PAINT ORANGE (-4175 2675);
DISPLAY INVISIBLE (-4175 2675);
FORCEADD OFFPAGE..6
(-3850 1900);
FORCEPROP 2 LAST $XR0 83 
J 0
(-4099 1900);
DISPLAY 0.638298 (-4099 1900);
PAINT MONO (-4099 1900);
FORCEPROP 2 LAST $XR1 84 
J 0
(-4189 1900);
DISPLAY 0.638298 (-4189 1900);
PAINT MONO (-4189 1900);
FORCEPROP 2 LAST $XR2 85 
J 0
(-4279 1900);
DISPLAY 0.638298 (-4279 1900);
PAINT MONO (-4279 1900);
FORCEPROP 2 LAST $XR3 86 
J 0
(-4369 1900);
DISPLAY 0.638298 (-4369 1900);
PAINT MONO (-4369 1900);
FORCEPROP 2 LAST $XR4 88 
J 0
(-4459 1900);
DISPLAY 0.638298 (-4459 1900);
PAINT MONO (-4459 1900);
FORCEPROP 2 LAST $XR5 99 
J 0
(-4549 1900);
DISPLAY 0.638298 (-4549 1900);
PAINT MONO (-4549 1900);
FORCEPROP 2 LASTPIN (-3800 1900) SIG_NAME SMB_DDR_KLM_VPP_SDA
J 0
(-3760 1910);
DISPLAY 0.617021 (-3760 1910);
PAINT ORANGE (-3760 1910);
FORCEPROP 2 LAST CDS_LIB mstr_standard
J 0
(-3850 1900);
DISPLAY 0.787234 (-3850 1900);
PAINT MONO (-3850 1900);
DISPLAY INVISIBLE (-3850 1900);
FORCEPROP 1 LAST OFFPAGE TRUE
J 0
(-3525 1775);
DISPLAY 0.936170 (-3525 1775);
PAINT GREEN (-3525 1775);
DISPLAY INVISIBLE (-3525 1775);
FORCEPROP 1 LAST COMMENT_BODY TRUE
J 0
(-3750 1825);
DISPLAY 0.936170 (-3750 1825);
PAINT GREEN (-3750 1825);
DISPLAY INVISIBLE (-3750 1825);
FORCEPROP 2 LAST PATH I172
J 0
(-4150 1950);
DISPLAY 0.787234 (-4150 1950);
PAINT ORANGE (-4150 1950);
DISPLAY INVISIBLE (-4150 1950);
FORCEADD OFFPAGE..1
(-4800 1750);
FORCEPROP 2 LAST $XR0 100 
J 0
(-5082 1750);
DISPLAY 0.638298 (-5082 1750);
PAINT MONO (-5082 1750);
FORCEPROP 2 LAST $XR1 88 
J 0
(-5172 1750);
DISPLAY 0.638298 (-5172 1750);
PAINT MONO (-5172 1750);
FORCEPROP 2 LAST CDS_LIB mstr_standard
J 0
(-4800 1750);
DISPLAY 0.787234 (-4800 1750);
PAINT MONO (-4800 1750);
DISPLAY INVISIBLE (-4800 1750);
FORCEPROP 1 LAST OFFPAGE TRUE
J 0
(-4475 1625);
DISPLAY 0.936170 (-4475 1625);
PAINT GREEN (-4475 1625);
DISPLAY INVISIBLE (-4475 1625);
FORCEPROP 1 LAST COMMENT_BODY TRUE
J 0
(-4675 1650);
DISPLAY 0.936170 (-4675 1650);
PAINT GREEN (-4675 1650);
DISPLAY INVISIBLE (-4675 1650);
FORCEPROP 2 LAST PATH I173
J 0
(-5050 1800);
DISPLAY 0.787234 (-5050 1800);
PAINT ORANGE (-5050 1800);
DISPLAY INVISIBLE (-5050 1800);
FORCEADD OFFPAGE..1
(-3850 1850);
FORCEPROP 2 LAST $XR0 99 
J 0
(-4101 1850);
DISPLAY 0.638298 (-4101 1850);
PAINT MONO (-4101 1850);
FORCEPROP 2 LAST $XR1 83 
J 0
(-4191 1850);
DISPLAY 0.638298 (-4191 1850);
PAINT MONO (-4191 1850);
FORCEPROP 2 LAST $XR2 84 
J 0
(-4281 1850);
DISPLAY 0.638298 (-4281 1850);
PAINT MONO (-4281 1850);
FORCEPROP 2 LAST $XR3 85 
J 0
(-4371 1850);
DISPLAY 0.638298 (-4371 1850);
PAINT MONO (-4371 1850);
FORCEPROP 2 LAST $XR4 86 
J 0
(-4461 1850);
DISPLAY 0.638298 (-4461 1850);
PAINT MONO (-4461 1850);
FORCEPROP 2 LAST $XR5 88 
J 0
(-4551 1850);
DISPLAY 0.638298 (-4551 1850);
PAINT MONO (-4551 1850);
FORCEPROP 2 LAST CDS_LIB mstr_standard
J 0
(-3850 1850);
DISPLAY 0.787234 (-3850 1850);
PAINT MONO (-3850 1850);
DISPLAY INVISIBLE (-3850 1850);
FORCEPROP 1 LAST OFFPAGE TRUE
J 0
(-3525 1725);
DISPLAY 0.936170 (-3525 1725);
PAINT GREEN (-3525 1725);
DISPLAY INVISIBLE (-3525 1725);
FORCEPROP 1 LAST COMMENT_BODY TRUE
J 0
(-3725 1750);
DISPLAY 0.936170 (-3725 1750);
PAINT GREEN (-3725 1750);
DISPLAY INVISIBLE (-3725 1750);
FORCEPROP 2 LAST PATH I174
J 0
(-4125 1900);
DISPLAY 0.787234 (-4125 1900);
PAINT ORANGE (-4125 1900);
DISPLAY INVISIBLE (-4125 1900);
FORCEADD GND..1
R 2
(-5000 1850);
FORCEPROP 3 LASTPIN (-5000 1900) SIG_NAME GND\g
J 0
(-4990 1910);
DISPLAY 0.659574 (-4990 1910);
PAINT MONO (-4990 1910);
DISPLAY INVISIBLE (-4990 1910);
FORCEPROP 1 LAST VOLTAGE 0
J 0
(-5000 1850);
PAINT SKYBLUE (-5000 1850);
DISPLAY INVISIBLE (-5000 1850);
FORCEPROP 2 LAST BOM_COST MEM
J 0
(-5000 1855);
PAINT ORANGE (-5000 1855);
DISPLAY INVISIBLE (-5000 1855);
FORCEPROP 2 LAST CDS_LIB mstr_symbols
J 0
(-5000 1850);
DISPLAY 0.787234 (-5000 1850);
PAINT MONO (-5000 1850);
DISPLAY INVISIBLE (-5000 1850);
FORCEPROP 1 LAST SIZE 1B
J 2
(-5075 1800);
DISPLAY 1.170213 (-5075 1800);
PAINT GREEN (-5075 1800);
DISPLAY INVISIBLE (-5075 1800);
FORCEPROP 1 LAST BODY_TYPE PLUMBING
J 2
(-4955 1807);
DISPLAY 0.340426 (-4955 1807);
PAINT GREEN (-4955 1807);
DISPLAY INVISIBLE (-4955 1807);
FORCEPROP 1 LAST PATH I176
J 2
(-5075 1850);
DISPLAY 1.404255 (-5075 1850);
PAINT GREEN (-5075 1850);
DISPLAY INVISIBLE (-5075 1850);
FORCEPROP 2 LAST ROOM DDR4_CH_D
J 0
(-5000 1855);
PAINT ORANGE (-5000 1855);
DISPLAY INVISIBLE (-5000 1855);
FORCEPROP 1 LAST HDL_POWER GND
J 2
(-5000 2000);
DISPLAY 0.553191 (-5000 2000);
PAINT GREEN (-5000 2000);
DISPLAY INVISIBLE (-5000 2000);
FORCEADD GND..1
(-4650 1300);
FORCEPROP 3 LASTPIN (-4650 1350) SIG_NAME GND\g
J 0
(-4640 1360);
DISPLAY 0.659574 (-4640 1360);
PAINT MONO (-4640 1360);
DISPLAY INVISIBLE (-4640 1360);
FORCEPROP 1 LAST VOLTAGE 16V
J 0
(-4650 1300);
PAINT SKYBLUE (-4650 1300);
DISPLAY INVISIBLE (-4650 1300);
FORCEPROP 2 LAST CDS_LIB mstr_symbols
J 0
(-4650 1300);
PAINT ORANGE (-4650 1300);
DISPLAY INVISIBLE (-4650 1300);
FORCEPROP 2 LAST BOM_COST MEM
J 0
(-4650 1305);
PAINT ORANGE (-4650 1305);
DISPLAY INVISIBLE (-4650 1305);
FORCEPROP 1 LAST SIZE 1B
J 0
(-4575 1250);
DISPLAY 1.787234 (-4575 1250);
PAINT GREEN (-4575 1250);
DISPLAY INVISIBLE (-4575 1250);
FORCEPROP 1 LAST BODY_TYPE PLUMBING
J 0
(-4695 1257);
DISPLAY 0.340426 (-4695 1257);
PAINT GREEN (-4695 1257);
DISPLAY INVISIBLE (-4695 1257);
FORCEPROP 1 LAST PATH I177
J 0
(-4575 1300);
DISPLAY 1.404255 (-4575 1300);
PAINT GREEN (-4575 1300);
DISPLAY INVISIBLE (-4575 1300);
FORCEPROP 2 LAST ROOM DDR4_CH_M1
J 0
(-4650 1305);
PAINT ORANGE (-4650 1305);
DISPLAY INVISIBLE (-4650 1305);
FORCEPROP 1 LAST HDL_POWER GND
J 0
(-4650 1450);
DISPLAY 1.404255 (-4650 1450);
PAINT GREEN (-4650 1450);
DISPLAY INVISIBLE (-4650 1450);
FORCEADD CAP_A..1
R 2
(-4650 1550);
FORCEPROP 1 LAST LOCATION C1A5
J 2
(-4700 1650);
DISPLAY 0.617021 (-4700 1650);
PAINT AQUA (-4700 1650);
FORCEPROP 1 LAST PART_NUMBER A36096-045
J 2
(-4700 1400);
DISPLAY 0.617021 (-4700 1400);
PAINT BLUE (-4700 1400);
FORCEPROP 1 LAST VALUE 0.01UF
J 2
(-4700 1600);
DISPLAY 0.617021 (-4700 1600);
PAINT SKYBLUE (-4700 1600);
FORCEPROP 1 LAST TOLERANCE 10%
J 2
(-4700 1500);
DISPLAY 0.617021 (-4700 1500);
PAINT SKYBLUE (-4700 1500);
FORCEPROP 1 LAST PACK_TYPE 0402V
J 2
(-4700 1350);
DISPLAY 0.617021 (-4700 1350);
PAINT SKYBLUE (-4700 1350);
FORCEPROP 1 LAST VOLTAGE 25V
J 2
(-4700 1550);
DISPLAY 0.617021 (-4700 1550);
PAINT SKYBLUE (-4700 1550);
FORCEPROP 1 LAST MATERIAL X7R
J 2
(-4700 1450);
DISPLAY 0.617021 (-4700 1450);
PAINT SKYBLUE (-4700 1450);
FORCEPROP 1 LASTPIN (-4650 1650) $PN 1
J 2
(-4660 1630);
DISPLAY 0.617021 (-4660 1630);
PAINT ORANGE (-4660 1630);
FORCEPROP 1 LASTPIN (-4650 1450) $PN 2
J 2
(-4660 1430);
DISPLAY 0.617021 (-4660 1430);
PAINT ORANGE (-4660 1430);
FORCEPROP 2 LAST CDS_LOCATION C1A5
J 2
(-4700 1650);
DISPLAY 0.617021 (-4700 1650);
PAINT AQUA (-4700 1650);
DISPLAY INVISIBLE (-4700 1650);
FORCEPROP 2 LAST BOM_COST MEM
J 0
(-4650 1550);
PAINT ORANGE (-4650 1550);
DISPLAY INVISIBLE (-4650 1550);
FORCEPROP 2 LAST CDS_LIB dev_discrete
J 0
(-4650 1550);
PAINT ORANGE (-4650 1550);
DISPLAY INVISIBLE (-4650 1550);
FORCEPROP 2 LAST CDS_SEC 1
J 0
(-4700 1700);
PAINT ORANGE (-4700 1700);
DISPLAY INVISIBLE (-4700 1700);
FORCEPROP 2 LAST SEC_TYPE 0402V
J 0
(-4700 1750);
DISPLAY 1.021277 (-4700 1750);
PAINT ORANGE (-4700 1750);
DISPLAY INVISIBLE (-4700 1750);
FORCEPROP 2 LAST SEC 1
J 0
(-4700 1750);
PAINT MONO (-4700 1750);
DISPLAY INVISIBLE (-4700 1750);
FORCEPROP 1 LAST PATH I178
J 2
(-4700 1700);
DISPLAY 0.978723 (-4700 1700);
PAINT WHITE (-4700 1700);
DISPLAY INVISIBLE (-4700 1700);
FORCEPROP 2 LAST ROOM DDR4_CH_M
J 0
(-4650 1550);
PAINT ORANGE (-4650 1550);
DISPLAY INVISIBLE (-4650 1550);
FORCEADD PVPP_KLM..1
(-1100 3050);
FORCEPROP 3 LASTPIN (-1100 3000) SIG_NAME PVPP_KLM\g
J 0
(-1090 3010);
DISPLAY 0.659574 (-1090 3010);
PAINT MONO (-1090 3010);
DISPLAY INVISIBLE (-1090 3010);
FORCEPROP 1 LAST VOLTAGE 2.5V
J 0
(-1145 3007);
DISPLAY 0.340426 (-1145 3007);
PAINT SKYBLUE (-1145 3007);
DISPLAY INVISIBLE (-1145 3007);
FORCEPROP 0 LAST BOM_COST MEM
J 0
(-1100 3150);
PAINT ORANGE (-1100 3150);
DISPLAY INVISIBLE (-1100 3150);
FORCEPROP 2 LAST CDS_LIB mstr_symbols
J 0
(-1100 3050);
PAINT ORANGE (-1100 3050);
DISPLAY INVISIBLE (-1100 3050);
FORCEPROP 1 LAST BODY_TYPE PLUMBING
J 0
(-1145 3007);
DISPLAY 0.340426 (-1145 3007);
PAINT GREEN (-1145 3007);
DISPLAY INVISIBLE (-1145 3007);
FORCEPROP 1 LAST PATH I179
J 0
(-1050 3075);
DISPLAY 0.872340 (-1050 3075);
PAINT AQUA (-1050 3075);
DISPLAY INVISIBLE (-1050 3075);
FORCEPROP 2 LAST ROOM DDR4_CH_D
J 0
(-1100 3150);
PAINT ORANGE (-1100 3150);
DISPLAY INVISIBLE (-1100 3150);
FORCEPROP 1 LAST HDL_POWER PVPP_KLM
J 1
(-1100 3100);
DISPLAY 0.872340 (-1100 3100);
PAINT GREEN (-1100 3100);
DISPLAY INVISIBLE (-1100 3100);
FORCEADD TAP..6
R 2
(900 3900);
FORCEPROP 3 LASTPIN (850 3900) SIG_NAME M_M_DQS_DN<5>
J 0
(860 3910);
DISPLAY 0.659574 (860 3910);
PAINT MONO (860 3910);
DISPLAY INVISIBLE (860 3910);
FORCEPROP 1 LASTPIN (850 3900) BN 5
J 2
(900 3910);
DISPLAY 0.617021 (900 3910);
PAINT PINK (900 3910);
FORCEPROP 2 LAST CDS_LIB mstr_standard
J 0
(900 3900);
DISPLAY 0.787234 (900 3900);
PAINT MONO (900 3900);
DISPLAY INVISIBLE (900 3900);
FORCEPROP 1 LAST BODY_TYPE PLUMBING
J 2
(900 3850);
DISPLAY 1.234043 (900 3850);
PAINT GREEN (900 3850);
DISPLAY INVISIBLE (900 3850);
FORCEPROP 1 LAST HDL_TAP TRUE
J 2
(575 3775);
DISPLAY 1.234043 (575 3775);
PAINT GREEN (575 3775);
DISPLAY INVISIBLE (575 3775);
FORCEPROP 1 LAST PATH I18
J 2
(900 3900);
DISPLAY 0.936170 (900 3900);
PAINT GREEN (900 3900);
DISPLAY INVISIBLE (900 3900);
FORCEADD PVPP_KLM..1
(-5000 2250);
FORCEPROP 3 LASTPIN (-5000 2200) SIG_NAME PVPP_KLM\g
J 0
(-4990 2210);
DISPLAY 0.659574 (-4990 2210);
PAINT MONO (-4990 2210);
DISPLAY INVISIBLE (-4990 2210);
FORCEPROP 1 LAST VOLTAGE 2.5V
J 0
(-5045 2207);
DISPLAY 0.340426 (-5045 2207);
PAINT SKYBLUE (-5045 2207);
DISPLAY INVISIBLE (-5045 2207);
FORCEPROP 0 LAST BOM_COST MEM
J 0
(-5000 2350);
PAINT ORANGE (-5000 2350);
DISPLAY INVISIBLE (-5000 2350);
FORCEPROP 2 LAST CDS_LIB mstr_symbols
J 0
(-5000 2250);
PAINT ORANGE (-5000 2250);
DISPLAY INVISIBLE (-5000 2250);
FORCEPROP 1 LAST BODY_TYPE PLUMBING
J 0
(-5045 2207);
DISPLAY 0.340426 (-5045 2207);
PAINT GREEN (-5045 2207);
DISPLAY INVISIBLE (-5045 2207);
FORCEPROP 1 LAST PATH I180
J 0
(-4950 2275);
DISPLAY 0.872340 (-4950 2275);
PAINT AQUA (-4950 2275);
DISPLAY INVISIBLE (-4950 2275);
FORCEPROP 2 LAST ROOM DDR4_CH_D
J 0
(-5000 2350);
PAINT ORANGE (-5000 2350);
DISPLAY INVISIBLE (-5000 2350);
FORCEPROP 1 LAST HDL_POWER PVPP_KLM
J 1
(-5000 2300);
DISPLAY 0.872340 (-5000 2300);
PAINT GREEN (-5000 2300);
DISPLAY INVISIBLE (-5000 2300);
FORCEADD OFFPAGE..1
(-3900 1450);
FORCEPROP 2 LAST $XR0 89 
J 0
(-4121 1450);
DISPLAY 0.638298 (-4121 1450);
PAINT MONO (-4121 1450);
FORCEPROP 2 LAST $XR1 83 
J 0
(-4211 1450);
DISPLAY 0.638298 (-4211 1450);
PAINT MONO (-4211 1450);
FORCEPROP 2 LAST $XR2 84 
J 0
(-4301 1450);
DISPLAY 0.638298 (-4301 1450);
PAINT MONO (-4301 1450);
FORCEPROP 2 LAST $XR3 85 
J 0
(-4391 1450);
DISPLAY 0.638298 (-4391 1450);
PAINT MONO (-4391 1450);
FORCEPROP 2 LAST $XR4 86 
J 0
(-4481 1450);
DISPLAY 0.638298 (-4481 1450);
PAINT MONO (-4481 1450);
FORCEPROP 2 LAST $XR5 88 
J 0
(-4571 1450);
DISPLAY 0.638298 (-4571 1450);
PAINT MONO (-4571 1450);
FORCEPROP 2 LAST CDS_LIB mstr_standard
J 0
(-3900 1450);
PAINT ORANGE (-3900 1450);
DISPLAY INVISIBLE (-3900 1450);
FORCEPROP 1 LAST OFFPAGE TRUE
J 0
(-3575 1325);
DISPLAY 0.936170 (-3575 1325);
PAINT GREEN (-3575 1325);
DISPLAY INVISIBLE (-3575 1325);
FORCEPROP 1 LAST COMMENT_BODY TRUE
J 0
(-3775 1350);
DISPLAY 0.936170 (-3775 1350);
PAINT GREEN (-3775 1350);
DISPLAY INVISIBLE (-3775 1350);
FORCEPROP 2 LAST PATH I181
J 0
(-3850 1525);
PAINT ORANGE (-3850 1525);
DISPLAY INVISIBLE (-3850 1525);
FORCEADD SCONN288_H44441004..3
(1800 2450);
FORCEPROP 1 LAST LOCATION J1A1
J 0
(1350 3850);
DISPLAY 0.617021 (1350 3850);
PAINT AQUA (1350 3850);
FORCEPROP 1 LAST PART_NUMBER H44441-004
J 0
(1350 1100);
DISPLAY 0.617021 (1350 1100);
PAINT BLUE (1350 1100);
FORCEPROP 1 LAST MATERIAL SCONN
J 0
(1350 3800);
DISPLAY 0.617021 (1350 3800);
PAINT SKYBLUE (1350 3800);
FORCEPROP 2 LASTPIN (1300 3600) $PN 2
J 2
(1290 3610);
DISPLAY 0.617021 (1290 3610);
PAINT ORANGE (1290 3610);
FORCEPROP 2 LASTPIN (1300 3550) $PN 4
J 2
(1290 3560);
DISPLAY 0.617021 (1290 3560);
PAINT ORANGE (1290 3560);
FORCEPROP 2 LASTPIN (1300 3500) $PN 6
J 2
(1290 3510);
DISPLAY 0.617021 (1290 3510);
PAINT ORANGE (1290 3510);
FORCEPROP 2 LASTPIN (1300 3450) $PN 9
J 2
(1290 3460);
DISPLAY 0.617021 (1290 3460);
PAINT ORANGE (1290 3460);
FORCEPROP 2 LASTPIN (1300 3400) $PN 11
J 2
(1290 3410);
DISPLAY 0.617021 (1290 3410);
PAINT ORANGE (1290 3410);
FORCEPROP 2 LASTPIN (1300 3350) $PN 13
J 2
(1290 3360);
DISPLAY 0.617021 (1290 3360);
PAINT ORANGE (1290 3360);
FORCEPROP 2 LASTPIN (1300 3300) $PN 15
J 2
(1290 3310);
DISPLAY 0.617021 (1290 3310);
PAINT ORANGE (1290 3310);
FORCEPROP 2 LASTPIN (1300 3250) $PN 17
J 2
(1290 3260);
DISPLAY 0.617021 (1290 3260);
PAINT ORANGE (1290 3260);
FORCEPROP 2 LASTPIN (1300 3200) $PN 20
J 2
(1290 3210);
DISPLAY 0.617021 (1290 3210);
PAINT ORANGE (1290 3210);
FORCEPROP 2 LASTPIN (1300 3150) $PN 22
J 2
(1290 3160);
DISPLAY 0.617021 (1290 3160);
PAINT ORANGE (1290 3160);
FORCEPROP 2 LASTPIN (1300 3100) $PN 24
J 2
(1290 3110);
DISPLAY 0.617021 (1290 3110);
PAINT ORANGE (1290 3110);
FORCEPROP 2 LASTPIN (1300 3050) $PN 26
J 2
(1290 3060);
DISPLAY 0.617021 (1290 3060);
PAINT ORANGE (1290 3060);
FORCEPROP 2 LASTPIN (1300 3000) $PN 28
J 2
(1290 3010);
DISPLAY 0.617021 (1290 3010);
PAINT ORANGE (1290 3010);
FORCEPROP 2 LASTPIN (1300 2950) $PN 31
J 2
(1290 2960);
DISPLAY 0.617021 (1290 2960);
PAINT ORANGE (1290 2960);
FORCEPROP 2 LASTPIN (1300 2900) $PN 33
J 2
(1290 2910);
DISPLAY 0.617021 (1290 2910);
PAINT ORANGE (1290 2910);
FORCEPROP 2 LASTPIN (1300 2850) $PN 35
J 2
(1290 2860);
DISPLAY 0.617021 (1290 2860);
PAINT ORANGE (1290 2860);
FORCEPROP 2 LASTPIN (1300 2800) $PN 37
J 2
(1290 2810);
DISPLAY 0.617021 (1290 2810);
PAINT ORANGE (1290 2810);
FORCEPROP 2 LASTPIN (1300 2750) $PN 39
J 2
(1290 2760);
DISPLAY 0.617021 (1290 2760);
PAINT ORANGE (1290 2760);
FORCEPROP 2 LASTPIN (1300 2700) $PN 42
J 2
(1290 2710);
DISPLAY 0.617021 (1290 2710);
PAINT ORANGE (1290 2710);
FORCEPROP 2 LASTPIN (1300 2650) $PN 44
J 2
(1290 2660);
DISPLAY 0.617021 (1290 2660);
PAINT ORANGE (1290 2660);
FORCEPROP 2 LASTPIN (1300 2600) $PN 46
J 2
(1290 2610);
DISPLAY 0.617021 (1290 2610);
PAINT ORANGE (1290 2610);
FORCEPROP 2 LASTPIN (1300 2550) $PN 48
J 2
(1290 2560);
DISPLAY 0.617021 (1290 2560);
PAINT ORANGE (1290 2560);
FORCEPROP 2 LASTPIN (1300 2500) $PN 50
J 2
(1290 2510);
DISPLAY 0.617021 (1290 2510);
PAINT ORANGE (1290 2510);
FORCEPROP 2 LASTPIN (1300 2450) $PN 53
J 2
(1290 2460);
DISPLAY 0.617021 (1290 2460);
PAINT ORANGE (1290 2460);
FORCEPROP 2 LASTPIN (1300 2400) $PN 55
J 2
(1290 2410);
DISPLAY 0.617021 (1290 2410);
PAINT ORANGE (1290 2410);
FORCEPROP 2 LASTPIN (1300 2350) $PN 57
J 2
(1290 2360);
DISPLAY 0.617021 (1290 2360);
PAINT ORANGE (1290 2360);
FORCEPROP 2 LASTPIN (1300 2300) $PN 94
J 2
(1290 2310);
DISPLAY 0.617021 (1290 2310);
PAINT ORANGE (1290 2310);
FORCEPROP 2 LASTPIN (1300 2250) $PN 96
J 2
(1290 2260);
DISPLAY 0.617021 (1290 2260);
PAINT ORANGE (1290 2260);
FORCEPROP 2 LASTPIN (1300 2200) $PN 98
J 2
(1290 2210);
DISPLAY 0.617021 (1290 2210);
PAINT ORANGE (1290 2210);
FORCEPROP 2 LASTPIN (1300 2150) $PN 101
J 2
(1290 2160);
DISPLAY 0.617021 (1290 2160);
PAINT ORANGE (1290 2160);
FORCEPROP 2 LASTPIN (1300 2100) $PN 103
J 2
(1290 2110);
DISPLAY 0.617021 (1290 2110);
PAINT ORANGE (1290 2110);
FORCEPROP 2 LASTPIN (1300 2050) $PN 105
J 2
(1290 2060);
DISPLAY 0.617021 (1290 2060);
PAINT ORANGE (1290 2060);
FORCEPROP 2 LASTPIN (1300 2000) $PN 107
J 2
(1290 2010);
DISPLAY 0.617021 (1290 2010);
PAINT ORANGE (1290 2010);
FORCEPROP 2 LASTPIN (1300 1950) $PN 109
J 2
(1290 1960);
DISPLAY 0.617021 (1290 1960);
PAINT ORANGE (1290 1960);
FORCEPROP 2 LASTPIN (1300 1900) $PN 112
J 2
(1290 1910);
DISPLAY 0.617021 (1290 1910);
PAINT ORANGE (1290 1910);
FORCEPROP 2 LASTPIN (1300 1850) $PN 114
J 2
(1290 1860);
DISPLAY 0.617021 (1290 1860);
PAINT ORANGE (1290 1860);
FORCEPROP 2 LASTPIN (1300 1800) $PN 116
J 2
(1290 1810);
DISPLAY 0.617021 (1290 1810);
PAINT ORANGE (1290 1810);
FORCEPROP 2 LASTPIN (1300 1750) $PN 118
J 2
(1290 1760);
DISPLAY 0.617021 (1290 1760);
PAINT ORANGE (1290 1760);
FORCEPROP 2 LASTPIN (1300 1700) $PN 120
J 2
(1290 1710);
DISPLAY 0.617021 (1290 1710);
PAINT ORANGE (1290 1710);
FORCEPROP 2 LASTPIN (1300 1650) $PN 123
J 2
(1290 1660);
DISPLAY 0.617021 (1290 1660);
PAINT ORANGE (1290 1660);
FORCEPROP 2 LASTPIN (1300 1600) $PN 125
J 2
(1290 1610);
DISPLAY 0.617021 (1290 1610);
PAINT ORANGE (1290 1610);
FORCEPROP 2 LASTPIN (1300 1550) $PN 127
J 2
(1290 1560);
DISPLAY 0.617021 (1290 1560);
PAINT ORANGE (1290 1560);
FORCEPROP 2 LASTPIN (1300 1500) $PN 129
J 2
(1290 1510);
DISPLAY 0.617021 (1290 1510);
PAINT ORANGE (1290 1510);
FORCEPROP 2 LASTPIN (1300 1450) $PN 131
J 2
(1290 1460);
DISPLAY 0.617021 (1290 1460);
PAINT ORANGE (1290 1460);
FORCEPROP 2 LASTPIN (1300 1400) $PN 134
J 2
(1290 1410);
DISPLAY 0.617021 (1290 1410);
PAINT ORANGE (1290 1410);
FORCEPROP 2 LASTPIN (1300 1350) $PN 136
J 2
(1290 1360);
DISPLAY 0.617021 (1290 1360);
PAINT ORANGE (1290 1360);
FORCEPROP 2 LASTPIN (1300 1300) $PN 138
J 2
(1290 1310);
DISPLAY 0.617021 (1290 1310);
PAINT ORANGE (1290 1310);
FORCEPROP 2 LASTPIN (2300 3600) $PN 147
J 0
(2310 3610);
DISPLAY 0.617021 (2310 3610);
PAINT ORANGE (2310 3610);
FORCEPROP 2 LASTPIN (2300 3550) $PN 149
J 0
(2310 3560);
DISPLAY 0.617021 (2310 3560);
PAINT ORANGE (2310 3560);
FORCEPROP 2 LASTPIN (2300 3500) $PN 151
J 0
(2310 3510);
DISPLAY 0.617021 (2310 3510);
PAINT ORANGE (2310 3510);
FORCEPROP 2 LASTPIN (2300 3450) $PN 154
J 0
(2310 3460);
DISPLAY 0.617021 (2310 3460);
PAINT ORANGE (2310 3460);
FORCEPROP 2 LASTPIN (2300 3400) $PN 156
J 0
(2310 3410);
DISPLAY 0.617021 (2310 3410);
PAINT ORANGE (2310 3410);
FORCEPROP 2 LASTPIN (2300 3350) $PN 158
J 0
(2310 3360);
DISPLAY 0.617021 (2310 3360);
PAINT ORANGE (2310 3360);
FORCEPROP 2 LASTPIN (2300 3300) $PN 160
J 0
(2310 3310);
DISPLAY 0.617021 (2310 3310);
PAINT ORANGE (2310 3310);
FORCEPROP 2 LASTPIN (2300 3250) $PN 162
J 0
(2310 3260);
DISPLAY 0.617021 (2310 3260);
PAINT ORANGE (2310 3260);
FORCEPROP 2 LASTPIN (2300 3200) $PN 165
J 0
(2310 3210);
DISPLAY 0.617021 (2310 3210);
PAINT ORANGE (2310 3210);
FORCEPROP 2 LASTPIN (2300 3150) $PN 167
J 0
(2310 3160);
DISPLAY 0.617021 (2310 3160);
PAINT ORANGE (2310 3160);
FORCEPROP 2 LASTPIN (2300 3100) $PN 169
J 0
(2310 3110);
DISPLAY 0.617021 (2310 3110);
PAINT ORANGE (2310 3110);
FORCEPROP 2 LASTPIN (2300 3050) $PN 171
J 0
(2310 3060);
DISPLAY 0.617021 (2310 3060);
PAINT ORANGE (2310 3060);
FORCEPROP 2 LASTPIN (2300 3000) $PN 173
J 0
(2310 3010);
DISPLAY 0.617021 (2310 3010);
PAINT ORANGE (2310 3010);
FORCEPROP 2 LASTPIN (2300 2950) $PN 176
J 0
(2310 2960);
DISPLAY 0.617021 (2310 2960);
PAINT ORANGE (2310 2960);
FORCEPROP 2 LASTPIN (2300 2900) $PN 178
J 0
(2310 2910);
DISPLAY 0.617021 (2310 2910);
PAINT ORANGE (2310 2910);
FORCEPROP 2 LASTPIN (2300 2850) $PN 180
J 0
(2310 2860);
DISPLAY 0.617021 (2310 2860);
PAINT ORANGE (2310 2860);
FORCEPROP 2 LASTPIN (2300 2800) $PN 182
J 0
(2310 2810);
DISPLAY 0.617021 (2310 2810);
PAINT ORANGE (2310 2810);
FORCEPROP 2 LASTPIN (2300 2750) $PN 184
J 0
(2310 2760);
DISPLAY 0.617021 (2310 2760);
PAINT ORANGE (2310 2760);
FORCEPROP 2 LASTPIN (2300 2700) $PN 187
J 0
(2310 2710);
DISPLAY 0.617021 (2310 2710);
PAINT ORANGE (2310 2710);
FORCEPROP 2 LASTPIN (2300 2650) $PN 189
J 0
(2310 2660);
DISPLAY 0.617021 (2310 2660);
PAINT ORANGE (2310 2660);
FORCEPROP 2 LASTPIN (2300 2600) $PN 191
J 0
(2310 2610);
DISPLAY 0.617021 (2310 2610);
PAINT ORANGE (2310 2610);
FORCEPROP 2 LASTPIN (2300 2550) $PN 193
J 0
(2310 2560);
DISPLAY 0.617021 (2310 2560);
PAINT ORANGE (2310 2560);
FORCEPROP 2 LASTPIN (2300 2500) $PN 195
J 0
(2310 2510);
DISPLAY 0.617021 (2310 2510);
PAINT ORANGE (2310 2510);
FORCEPROP 2 LASTPIN (2300 2450) $PN 198
J 0
(2310 2460);
DISPLAY 0.617021 (2310 2460);
PAINT ORANGE (2310 2460);
FORCEPROP 2 LASTPIN (2300 2400) $PN 200
J 0
(2310 2410);
DISPLAY 0.617021 (2310 2410);
PAINT ORANGE (2310 2410);
FORCEPROP 2 LASTPIN (2300 2350) $PN 202
J 0
(2310 2360);
DISPLAY 0.617021 (2310 2360);
PAINT ORANGE (2310 2360);
FORCEPROP 2 LASTPIN (2300 2300) $PN 239
J 0
(2310 2310);
DISPLAY 0.617021 (2310 2310);
PAINT ORANGE (2310 2310);
FORCEPROP 2 LASTPIN (2300 2250) $PN 241
J 0
(2310 2260);
DISPLAY 0.617021 (2310 2260);
PAINT ORANGE (2310 2260);
FORCEPROP 2 LASTPIN (2300 2200) $PN 243
J 0
(2310 2210);
DISPLAY 0.617021 (2310 2210);
PAINT ORANGE (2310 2210);
FORCEPROP 2 LASTPIN (2300 2150) $PN 246
J 0
(2310 2160);
DISPLAY 0.617021 (2310 2160);
PAINT ORANGE (2310 2160);
FORCEPROP 2 LASTPIN (2300 2100) $PN 248
J 0
(2310 2110);
DISPLAY 0.617021 (2310 2110);
PAINT ORANGE (2310 2110);
FORCEPROP 2 LASTPIN (2300 2050) $PN 250
J 0
(2310 2060);
DISPLAY 0.617021 (2310 2060);
PAINT ORANGE (2310 2060);
FORCEPROP 2 LASTPIN (2300 2000) $PN 252
J 0
(2310 2010);
DISPLAY 0.617021 (2310 2010);
PAINT ORANGE (2310 2010);
FORCEPROP 2 LASTPIN (2300 1950) $PN 254
J 0
(2310 1960);
DISPLAY 0.617021 (2310 1960);
PAINT ORANGE (2310 1960);
FORCEPROP 2 LASTPIN (2300 1900) $PN 257
J 0
(2310 1910);
DISPLAY 0.617021 (2310 1910);
PAINT ORANGE (2310 1910);
FORCEPROP 2 LASTPIN (2300 1850) $PN 259
J 0
(2310 1860);
DISPLAY 0.617021 (2310 1860);
PAINT ORANGE (2310 1860);
FORCEPROP 2 LASTPIN (2300 1800) $PN 261
J 0
(2310 1810);
DISPLAY 0.617021 (2310 1810);
PAINT ORANGE (2310 1810);
FORCEPROP 2 LASTPIN (2300 1750) $PN 263
J 0
(2310 1760);
DISPLAY 0.617021 (2310 1760);
PAINT ORANGE (2310 1760);
FORCEPROP 2 LASTPIN (2300 1700) $PN 265
J 0
(2310 1710);
DISPLAY 0.617021 (2310 1710);
PAINT ORANGE (2310 1710);
FORCEPROP 2 LASTPIN (2300 1650) $PN 268
J 0
(2310 1660);
DISPLAY 0.617021 (2310 1660);
PAINT ORANGE (2310 1660);
FORCEPROP 2 LASTPIN (2300 1600) $PN 270
J 0
(2310 1610);
DISPLAY 0.617021 (2310 1610);
PAINT ORANGE (2310 1610);
FORCEPROP 2 LASTPIN (2300 1550) $PN 272
J 0
(2310 1560);
DISPLAY 0.617021 (2310 1560);
PAINT ORANGE (2310 1560);
FORCEPROP 2 LASTPIN (2300 1500) $PN 274
J 0
(2310 1510);
DISPLAY 0.617021 (2310 1510);
PAINT ORANGE (2310 1510);
FORCEPROP 2 LASTPIN (2300 1450) $PN 276
J 0
(2310 1460);
DISPLAY 0.617021 (2310 1460);
PAINT ORANGE (2310 1460);
FORCEPROP 2 LASTPIN (2300 1400) $PN 279
J 0
(2310 1410);
DISPLAY 0.617021 (2310 1410);
PAINT ORANGE (2310 1410);
FORCEPROP 2 LASTPIN (2300 1350) $PN 281
J 0
(2310 1360);
DISPLAY 0.617021 (2310 1360);
PAINT ORANGE (2310 1360);
FORCEPROP 2 LASTPIN (2300 1300) $PN 283
J 0
(2310 1310);
DISPLAY 0.617021 (2310 1310);
PAINT ORANGE (2310 1310);
FORCEPROP 1 LAST PACK_TYPE PIP
J 0
(1350 3900);
PAINT SKYBLUE (1350 3900);
DISPLAY INVISIBLE (1350 3900);
FORCEPROP 2 LAST BOM_COST MEM
J 0
(1800 2450);
PAINT ORANGE (1800 2450);
DISPLAY INVISIBLE (1800 2450);
FORCEPROP 2 LAST CDS_LIB mstr_sconn
J 0
(1800 2450);
PAINT ORANGE (1800 2450);
DISPLAY INVISIBLE (1800 2450);
FORCEPROP 2 LAST SEC_TYPE PIP
J 0
(1350 3900);
DISPLAY 1.021277 (1350 3900);
PAINT ORANGE (1350 3900);
DISPLAY INVISIBLE (1350 3900);
FORCEPROP 2 LAST SEC 3
J 0
(1350 3900);
DISPLAY 0.680851 (1350 3900);
PAINT MONO (1350 3900);
DISPLAY INVISIBLE (1350 3900);
FORCEPROP 2 LAST CDS_LOCATION J1A1
J 0
(1350 3850);
DISPLAY 0.617021 (1350 3850);
PAINT AQUA (1350 3850);
DISPLAY INVISIBLE (1350 3850);
FORCEPROP 1 LAST PATH I185
J 0
(1800 3800);
PAINT GREEN (1800 3800);
DISPLAY INVISIBLE (1800 3800);
FORCEPROP 2 LAST ROOM DDR4_CH_M
J 0
(1800 2450);
PAINT ORANGE (1800 2450);
DISPLAY INVISIBLE (1800 2450);
FORCEADD SCONN288_H44441004..1
(-2500 3250);
FORCEPROP 1 LAST LOCATION J1A1
J 0
(-2950 5150);
DISPLAY 0.617021 (-2950 5150);
PAINT AQUA (-2950 5150);
FORCEPROP 1 LAST PART_NUMBER H44441-004
J 0
(-2950 1250);
DISPLAY 0.617021 (-2950 1250);
PAINT BLUE (-2950 1250);
FORCEPROP 1 LAST MATERIAL SCONN
J 0
(-2950 5100);
DISPLAY 0.617021 (-2950 5100);
PAINT SKYBLUE (-2950 5100);
FORCEPROP 2 LASTPIN (-3000 1750) $PN 146
J 2
(-3010 1760);
DISPLAY 0.617021 (-3010 1760);
PAINT ORANGE (-3010 1760);
FORCEPROP 2 LASTPIN (-3000 2100) $PN 284
J 2
(-3010 2110);
DISPLAY 0.617021 (-3010 2110);
PAINT ORANGE (-3010 2110);
FORCEPROP 2 LASTPIN (-3000 1900) $PN 285
J 2
(-3010 1910);
DISPLAY 0.617021 (-3010 1910);
PAINT ORANGE (-3010 1910);
FORCEPROP 2 LASTPIN (-3000 1850) $PN 141
J 2
(-3010 1860);
DISPLAY 0.617021 (-3010 1860);
PAINT ORANGE (-3010 1860);
FORCEPROP 2 LASTPIN (-3000 1450) $PN 230
J 2
(-3010 1460);
DISPLAY 0.617021 (-3010 1460);
PAINT ORANGE (-3010 1460);
FORCEPROP 2 LASTPIN (-3000 2050) $PN 238
J 2
(-3010 2060);
DISPLAY 0.617021 (-3010 2060);
PAINT ORANGE (-3010 2060);
FORCEPROP 2 LASTPIN (-3000 2000) $PN 140
J 2
(-3010 2010);
DISPLAY 0.617021 (-3010 2010);
PAINT ORANGE (-3010 2010);
FORCEPROP 2 LASTPIN (-3000 1950) $PN 139
J 2
(-3010 1960);
DISPLAY 0.617021 (-3010 1960);
PAINT ORANGE (-3010 1960);
FORCEPROP 2 LASTPIN (-3000 3400) $PN 237
J 2
(-3010 3410);
DISPLAY 0.617021 (-3010 3410);
PAINT ORANGE (-3010 3410);
FORCEPROP 2 LASTPIN (-3000 3350) $PN 93
J 2
(-3010 3360);
DISPLAY 0.617021 (-3010 3360);
PAINT ORANGE (-3010 3360);
FORCEPROP 2 LASTPIN (-3000 3300) $PN 89
J 2
(-3010 3310);
DISPLAY 0.617021 (-3010 3310);
PAINT ORANGE (-3010 3310);
FORCEPROP 2 LASTPIN (-3000 3250) $PN 84
J 2
(-3010 3260);
DISPLAY 0.617021 (-3010 3260);
PAINT ORANGE (-3010 3260);
FORCEPROP 2 LASTPIN (-3000 1650) $PN 144
J 2
(-3010 1660);
DISPLAY 0.617021 (-3010 1660);
PAINT ORANGE (-3010 1660);
FORCEPROP 2 LASTPIN (-3000 1600) $PN 227
J 2
(-3010 1610);
DISPLAY 0.617021 (-3010 1610);
PAINT ORANGE (-3010 1610);
FORCEPROP 2 LASTPIN (-3000 1550) $PN 205
J 2
(-3010 1560);
DISPLAY 0.617021 (-3010 1560);
PAINT ORANGE (-3010 1560);
FORCEPROP 2 LASTPIN (-3000 2350) $PN 58
J 2
(-3010 2360);
DISPLAY 0.617021 (-3010 2360);
PAINT ORANGE (-3010 2360);
FORCEPROP 2 LASTPIN (-3000 2400) $PN 222
J 2
(-3010 2410);
DISPLAY 0.617021 (-3010 2410);
PAINT ORANGE (-3010 2410);
FORCEPROP 2 LASTPIN (-3000 3000) $PN 91
J 2
(-3010 3010);
DISPLAY 0.617021 (-3010 3010);
PAINT ORANGE (-3010 3010);
FORCEPROP 2 LASTPIN (-3000 2950) $PN 87
J 2
(-3010 2960);
DISPLAY 0.617021 (-3010 2960);
PAINT ORANGE (-3010 2960);
FORCEPROP 2 LASTPIN (-3000 2300) $PN 78
J 2
(-3010 2310);
DISPLAY 0.617021 (-3010 2310);
PAINT ORANGE (-3010 2310);
FORCEPROP 2 LASTPIN (-2000 4900) $PN 280
J 0
(-1990 4910);
DISPLAY 0.617021 (-1990 4910);
PAINT ORANGE (-1990 4910);
FORCEPROP 2 LASTPIN (-2000 4850) $PN 135
J 0
(-1990 4860);
DISPLAY 0.617021 (-1990 4860);
PAINT ORANGE (-1990 4860);
FORCEPROP 2 LASTPIN (-2000 4800) $PN 273
J 0
(-1990 4810);
DISPLAY 0.617021 (-1990 4810);
PAINT ORANGE (-1990 4810);
FORCEPROP 2 LASTPIN (-2000 4750) $PN 128
J 0
(-1990 4760);
DISPLAY 0.617021 (-1990 4760);
PAINT ORANGE (-1990 4760);
FORCEPROP 2 LASTPIN (-2000 4700) $PN 282
J 0
(-1990 4710);
DISPLAY 0.617021 (-1990 4710);
PAINT ORANGE (-1990 4710);
FORCEPROP 2 LASTPIN (-2000 4650) $PN 137
J 0
(-1990 4660);
DISPLAY 0.617021 (-1990 4660);
PAINT ORANGE (-1990 4660);
FORCEPROP 2 LASTPIN (-2000 4600) $PN 275
J 0
(-1990 4610);
DISPLAY 0.617021 (-1990 4610);
PAINT ORANGE (-1990 4610);
FORCEPROP 2 LASTPIN (-2000 4550) $PN 130
J 0
(-1990 4560);
DISPLAY 0.617021 (-1990 4560);
PAINT ORANGE (-1990 4560);
FORCEPROP 2 LASTPIN (-2000 4500) $PN 269
J 0
(-1990 4510);
DISPLAY 0.617021 (-1990 4510);
PAINT ORANGE (-1990 4510);
FORCEPROP 2 LASTPIN (-2000 4450) $PN 124
J 0
(-1990 4460);
DISPLAY 0.617021 (-1990 4460);
PAINT ORANGE (-1990 4460);
FORCEPROP 2 LASTPIN (-2000 4400) $PN 262
J 0
(-1990 4410);
DISPLAY 0.617021 (-1990 4410);
PAINT ORANGE (-1990 4410);
FORCEPROP 2 LASTPIN (-2000 4350) $PN 117
J 0
(-1990 4360);
DISPLAY 0.617021 (-1990 4360);
PAINT ORANGE (-1990 4360);
FORCEPROP 2 LASTPIN (-2000 4300) $PN 271
J 0
(-1990 4310);
DISPLAY 0.617021 (-1990 4310);
PAINT ORANGE (-1990 4310);
FORCEPROP 2 LASTPIN (-2000 4250) $PN 126
J 0
(-1990 4260);
DISPLAY 0.617021 (-1990 4260);
PAINT ORANGE (-1990 4260);
FORCEPROP 2 LASTPIN (-2000 4200) $PN 264
J 0
(-1990 4210);
DISPLAY 0.617021 (-1990 4210);
PAINT ORANGE (-1990 4210);
FORCEPROP 2 LASTPIN (-2000 4150) $PN 119
J 0
(-1990 4160);
DISPLAY 0.617021 (-1990 4160);
PAINT ORANGE (-1990 4160);
FORCEPROP 2 LASTPIN (-2000 4100) $PN 258
J 0
(-1990 4110);
DISPLAY 0.617021 (-1990 4110);
PAINT ORANGE (-1990 4110);
FORCEPROP 2 LASTPIN (-2000 4050) $PN 113
J 0
(-1990 4060);
DISPLAY 0.617021 (-1990 4060);
PAINT ORANGE (-1990 4060);
FORCEPROP 2 LASTPIN (-2000 4000) $PN 251
J 0
(-1990 4010);
DISPLAY 0.617021 (-1990 4010);
PAINT ORANGE (-1990 4010);
FORCEPROP 2 LASTPIN (-2000 3950) $PN 106
J 0
(-1990 3960);
DISPLAY 0.617021 (-1990 3960);
PAINT ORANGE (-1990 3960);
FORCEPROP 2 LASTPIN (-2000 3900) $PN 260
J 0
(-1990 3910);
DISPLAY 0.617021 (-1990 3910);
PAINT ORANGE (-1990 3910);
FORCEPROP 2 LASTPIN (-2000 3850) $PN 115
J 0
(-1990 3860);
DISPLAY 0.617021 (-1990 3860);
PAINT ORANGE (-1990 3860);
FORCEPROP 2 LASTPIN (-2000 3800) $PN 253
J 0
(-1990 3810);
DISPLAY 0.617021 (-1990 3810);
PAINT ORANGE (-1990 3810);
FORCEPROP 2 LASTPIN (-2000 3750) $PN 108
J 0
(-1990 3760);
DISPLAY 0.617021 (-1990 3760);
PAINT ORANGE (-1990 3760);
FORCEPROP 2 LASTPIN (-2000 3700) $PN 247
J 0
(-1990 3710);
DISPLAY 0.617021 (-1990 3710);
PAINT ORANGE (-1990 3710);
FORCEPROP 2 LASTPIN (-2000 3650) $PN 102
J 0
(-1990 3660);
DISPLAY 0.617021 (-1990 3660);
PAINT ORANGE (-1990 3660);
FORCEPROP 2 LASTPIN (-2000 3600) $PN 240
J 0
(-1990 3610);
DISPLAY 0.617021 (-1990 3610);
PAINT ORANGE (-1990 3610);
FORCEPROP 2 LASTPIN (-2000 3550) $PN 95
J 0
(-1990 3560);
DISPLAY 0.617021 (-1990 3560);
PAINT ORANGE (-1990 3560);
FORCEPROP 2 LASTPIN (-2000 3500) $PN 249
J 0
(-1990 3510);
DISPLAY 0.617021 (-1990 3510);
PAINT ORANGE (-1990 3510);
FORCEPROP 2 LASTPIN (-2000 3450) $PN 104
J 0
(-1990 3460);
DISPLAY 0.617021 (-1990 3460);
PAINT ORANGE (-1990 3460);
FORCEPROP 2 LASTPIN (-2000 3400) $PN 242
J 0
(-1990 3410);
DISPLAY 0.617021 (-1990 3410);
PAINT ORANGE (-1990 3410);
FORCEPROP 2 LASTPIN (-2000 3350) $PN 97
J 0
(-1990 3360);
DISPLAY 0.617021 (-1990 3360);
PAINT ORANGE (-1990 3360);
FORCEPROP 2 LASTPIN (-2000 3300) $PN 188
J 0
(-1990 3310);
DISPLAY 0.617021 (-1990 3310);
PAINT ORANGE (-1990 3310);
FORCEPROP 2 LASTPIN (-2000 3250) $PN 43
J 0
(-1990 3260);
DISPLAY 0.617021 (-1990 3260);
PAINT ORANGE (-1990 3260);
FORCEPROP 2 LASTPIN (-2000 3200) $PN 181
J 0
(-1990 3210);
DISPLAY 0.617021 (-1990 3210);
PAINT ORANGE (-1990 3210);
FORCEPROP 2 LASTPIN (-2000 3150) $PN 36
J 0
(-1990 3160);
DISPLAY 0.617021 (-1990 3160);
PAINT ORANGE (-1990 3160);
FORCEPROP 2 LASTPIN (-2000 3100) $PN 190
J 0
(-1990 3110);
DISPLAY 0.617021 (-1990 3110);
PAINT ORANGE (-1990 3110);
FORCEPROP 2 LASTPIN (-2000 3050) $PN 45
J 0
(-1990 3060);
DISPLAY 0.617021 (-1990 3060);
PAINT ORANGE (-1990 3060);
FORCEPROP 2 LASTPIN (-2000 3000) $PN 183
J 0
(-1990 3010);
DISPLAY 0.617021 (-1990 3010);
PAINT ORANGE (-1990 3010);
FORCEPROP 2 LASTPIN (-2000 2950) $PN 38
J 0
(-1990 2960);
DISPLAY 0.617021 (-1990 2960);
PAINT ORANGE (-1990 2960);
FORCEPROP 2 LASTPIN (-2000 2900) $PN 177
J 0
(-1990 2910);
DISPLAY 0.617021 (-1990 2910);
PAINT ORANGE (-1990 2910);
FORCEPROP 2 LASTPIN (-2000 2850) $PN 32
J 0
(-1990 2860);
DISPLAY 0.617021 (-1990 2860);
PAINT ORANGE (-1990 2860);
FORCEPROP 2 LASTPIN (-2000 2800) $PN 170
J 0
(-1990 2810);
DISPLAY 0.617021 (-1990 2810);
PAINT ORANGE (-1990 2810);
FORCEPROP 2 LASTPIN (-2000 2750) $PN 25
J 0
(-1990 2760);
DISPLAY 0.617021 (-1990 2760);
PAINT ORANGE (-1990 2760);
FORCEPROP 2 LASTPIN (-2000 2700) $PN 179
J 0
(-1990 2710);
DISPLAY 0.617021 (-1990 2710);
PAINT ORANGE (-1990 2710);
FORCEPROP 2 LASTPIN (-2000 2650) $PN 34
J 0
(-1990 2660);
DISPLAY 0.617021 (-1990 2660);
PAINT ORANGE (-1990 2660);
FORCEPROP 2 LASTPIN (-2000 2600) $PN 172
J 0
(-1990 2610);
DISPLAY 0.617021 (-1990 2610);
PAINT ORANGE (-1990 2610);
FORCEPROP 2 LASTPIN (-2000 2550) $PN 27
J 0
(-1990 2560);
DISPLAY 0.617021 (-1990 2560);
PAINT ORANGE (-1990 2560);
FORCEPROP 2 LASTPIN (-2000 2500) $PN 166
J 0
(-1990 2510);
DISPLAY 0.617021 (-1990 2510);
PAINT ORANGE (-1990 2510);
FORCEPROP 2 LASTPIN (-2000 2450) $PN 21
J 0
(-1990 2460);
DISPLAY 0.617021 (-1990 2460);
PAINT ORANGE (-1990 2460);
FORCEPROP 2 LASTPIN (-2000 2400) $PN 159
J 0
(-1990 2410);
DISPLAY 0.617021 (-1990 2410);
PAINT ORANGE (-1990 2410);
FORCEPROP 2 LASTPIN (-2000 2350) $PN 14
J 0
(-1990 2360);
DISPLAY 0.617021 (-1990 2360);
PAINT ORANGE (-1990 2360);
FORCEPROP 2 LASTPIN (-2000 2300) $PN 168
J 0
(-1990 2310);
DISPLAY 0.617021 (-1990 2310);
PAINT ORANGE (-1990 2310);
FORCEPROP 2 LASTPIN (-2000 2250) $PN 23
J 0
(-1990 2260);
DISPLAY 0.617021 (-1990 2260);
PAINT ORANGE (-1990 2260);
FORCEPROP 2 LASTPIN (-2000 2200) $PN 161
J 0
(-1990 2210);
DISPLAY 0.617021 (-1990 2210);
PAINT ORANGE (-1990 2210);
FORCEPROP 2 LASTPIN (-2000 2150) $PN 16
J 0
(-1990 2160);
DISPLAY 0.617021 (-1990 2160);
PAINT ORANGE (-1990 2160);
FORCEPROP 2 LASTPIN (-2000 2100) $PN 155
J 0
(-1990 2110);
DISPLAY 0.617021 (-1990 2110);
PAINT ORANGE (-1990 2110);
FORCEPROP 2 LASTPIN (-2000 2050) $PN 10
J 0
(-1990 2060);
DISPLAY 0.617021 (-1990 2060);
PAINT ORANGE (-1990 2060);
FORCEPROP 2 LASTPIN (-2000 2000) $PN 148
J 0
(-1990 2010);
DISPLAY 0.617021 (-1990 2010);
PAINT ORANGE (-1990 2010);
FORCEPROP 2 LASTPIN (-2000 1950) $PN 3
J 0
(-1990 1960);
DISPLAY 0.617021 (-1990 1960);
PAINT ORANGE (-1990 1960);
FORCEPROP 2 LASTPIN (-2000 1900) $PN 157
J 0
(-1990 1910);
DISPLAY 0.617021 (-1990 1910);
PAINT ORANGE (-1990 1910);
FORCEPROP 2 LASTPIN (-2000 1850) $PN 12
J 0
(-1990 1860);
DISPLAY 0.617021 (-1990 1860);
PAINT ORANGE (-1990 1860);
FORCEPROP 2 LASTPIN (-2000 1800) $PN 150
J 0
(-1990 1810);
DISPLAY 0.617021 (-1990 1810);
PAINT ORANGE (-1990 1810);
FORCEPROP 2 LASTPIN (-2000 1750) $PN 5
J 0
(-1990 1760);
DISPLAY 0.617021 (-1990 1760);
PAINT ORANGE (-1990 1760);
FORCEPROP 2 LASTPIN (-3000 3150) $PN 203
J 2
(-3010 3160);
DISPLAY 0.617021 (-3010 3160);
PAINT ORANGE (-3010 3160);
FORCEPROP 2 LASTPIN (-3000 3100) $PN 60
J 2
(-3010 3110);
DISPLAY 0.617021 (-3010 3110);
PAINT ORANGE (-3010 3110);
FORCEPROP 2 LASTPIN (-3000 3700) $PN 218
J 2
(-3010 3710);
DISPLAY 0.617021 (-3010 3710);
PAINT ORANGE (-3010 3710);
FORCEPROP 2 LASTPIN (-3000 3650) $PN 219
J 2
(-3010 3660);
DISPLAY 0.617021 (-3010 3660);
PAINT ORANGE (-3010 3660);
FORCEPROP 2 LASTPIN (-3000 3600) $PN 74
J 2
(-3010 3610);
DISPLAY 0.617021 (-3010 3610);
PAINT ORANGE (-3010 3610);
FORCEPROP 2 LASTPIN (-3000 3550) $PN 75
J 2
(-3010 3560);
DISPLAY 0.617021 (-3010 3560);
PAINT ORANGE (-3010 3560);
FORCEPROP 2 LASTPIN (-3000 2850) $PN 199
J 2
(-3010 2860);
DISPLAY 0.617021 (-3010 2860);
PAINT ORANGE (-3010 2860);
FORCEPROP 2 LASTPIN (-3000 2800) $PN 54
J 2
(-3010 2810);
DISPLAY 0.617021 (-3010 2810);
PAINT ORANGE (-3010 2810);
FORCEPROP 2 LASTPIN (-3000 2750) $PN 192
J 2
(-3010 2760);
DISPLAY 0.617021 (-3010 2760);
PAINT ORANGE (-3010 2760);
FORCEPROP 2 LASTPIN (-3000 2700) $PN 47
J 2
(-3010 2710);
DISPLAY 0.617021 (-3010 2710);
PAINT ORANGE (-3010 2710);
FORCEPROP 2 LASTPIN (-3000 2650) $PN 201
J 2
(-3010 2660);
DISPLAY 0.617021 (-3010 2660);
PAINT ORANGE (-3010 2660);
FORCEPROP 2 LASTPIN (-3000 2600) $PN 56
J 2
(-3010 2610);
DISPLAY 0.617021 (-3010 2610);
PAINT ORANGE (-3010 2610);
FORCEPROP 2 LASTPIN (-3000 2550) $PN 194
J 2
(-3010 2560);
DISPLAY 0.617021 (-3010 2560);
PAINT ORANGE (-3010 2560);
FORCEPROP 2 LASTPIN (-3000 2500) $PN 49
J 2
(-3010 2510);
DISPLAY 0.617021 (-3010 2510);
PAINT ORANGE (-3010 2510);
FORCEPROP 2 LASTPIN (-3000 3450) $PN 235
J 2
(-3010 3460);
DISPLAY 0.617021 (-3010 3460);
PAINT ORANGE (-3010 3460);
FORCEPROP 2 LASTPIN (-3000 3850) $PN 207
J 2
(-3010 3860);
DISPLAY 0.617021 (-3010 3860);
PAINT ORANGE (-3010 3860);
FORCEPROP 2 LASTPIN (-3000 3800) $PN 63
J 2
(-3010 3810);
DISPLAY 0.617021 (-3010 3810);
PAINT ORANGE (-3010 3810);
FORCEPROP 2 LASTPIN (-3000 3950) $PN 224
J 2
(-3010 3960);
DISPLAY 0.617021 (-3010 3960);
PAINT ORANGE (-3010 3960);
FORCEPROP 2 LASTPIN (-3000 3900) $PN 81
J 2
(-3010 3910);
DISPLAY 0.617021 (-3010 3910);
PAINT ORANGE (-3010 3910);
FORCEPROP 2 LASTPIN (-3000 2250) $PN 208
J 2
(-3010 2260);
DISPLAY 0.617021 (-3010 2260);
PAINT ORANGE (-3010 2260);
FORCEPROP 2 LASTPIN (-3000 2200) $PN 62
J 2
(-3010 2210);
DISPLAY 0.617021 (-3010 2210);
PAINT ORANGE (-3010 2210);
FORCEPROP 2 LASTPIN (-3000 4900) $PN 234
J 2
(-3010 4910);
DISPLAY 0.617021 (-3010 4910);
PAINT ORANGE (-3010 4910);
FORCEPROP 2 LASTPIN (-3000 4850) $PN 82
J 2
(-3010 4860);
DISPLAY 0.617021 (-3010 4860);
PAINT ORANGE (-3010 4860);
FORCEPROP 2 LASTPIN (-3000 4800) $PN 86
J 2
(-3010 4810);
DISPLAY 0.617021 (-3010 4810);
PAINT ORANGE (-3010 4810);
FORCEPROP 2 LASTPIN (-3000 4750) $PN 228
J 2
(-3010 4760);
DISPLAY 0.617021 (-3010 4760);
PAINT ORANGE (-3010 4760);
FORCEPROP 2 LASTPIN (-3000 4700) $PN 232
J 2
(-3010 4710);
DISPLAY 0.617021 (-3010 4710);
PAINT ORANGE (-3010 4710);
FORCEPROP 2 LASTPIN (-3000 4650) $PN 65
J 2
(-3010 4660);
DISPLAY 0.617021 (-3010 4660);
PAINT ORANGE (-3010 4660);
FORCEPROP 2 LASTPIN (-3000 4600) $PN 210
J 2
(-3010 4610);
DISPLAY 0.617021 (-3010 4610);
PAINT ORANGE (-3010 4610);
FORCEPROP 2 LASTPIN (-3000 4550) $PN 225
J 2
(-3010 4560);
DISPLAY 0.617021 (-3010 4560);
PAINT ORANGE (-3010 4560);
FORCEPROP 2 LASTPIN (-3000 4500) $PN 66
J 2
(-3010 4510);
DISPLAY 0.617021 (-3010 4510);
PAINT ORANGE (-3010 4510);
FORCEPROP 2 LASTPIN (-3000 4450) $PN 68
J 2
(-3010 4460);
DISPLAY 0.617021 (-3010 4460);
PAINT ORANGE (-3010 4460);
FORCEPROP 2 LASTPIN (-3000 4400) $PN 211
J 2
(-3010 4410);
DISPLAY 0.617021 (-3010 4410);
PAINT ORANGE (-3010 4410);
FORCEPROP 2 LASTPIN (-3000 4350) $PN 69
J 2
(-3010 4360);
DISPLAY 0.617021 (-3010 4360);
PAINT ORANGE (-3010 4360);
FORCEPROP 2 LASTPIN (-3000 4300) $PN 213
J 2
(-3010 4310);
DISPLAY 0.617021 (-3010 4310);
PAINT ORANGE (-3010 4310);
FORCEPROP 2 LASTPIN (-3000 4250) $PN 214
J 2
(-3010 4260);
DISPLAY 0.617021 (-3010 4260);
PAINT ORANGE (-3010 4260);
FORCEPROP 2 LASTPIN (-3000 4200) $PN 71
J 2
(-3010 4210);
DISPLAY 0.617021 (-3010 4210);
PAINT ORANGE (-3010 4210);
FORCEPROP 2 LASTPIN (-3000 4150) $PN 216
J 2
(-3010 4160);
DISPLAY 0.617021 (-3010 4160);
PAINT ORANGE (-3010 4160);
FORCEPROP 2 LASTPIN (-3000 4100) $PN 72
J 2
(-3010 4110);
DISPLAY 0.617021 (-3010 4110);
PAINT ORANGE (-3010 4110);
FORCEPROP 2 LASTPIN (-3000 4050) $PN 79
J 2
(-3010 4060);
DISPLAY 0.617021 (-3010 4060);
PAINT ORANGE (-3010 4060);
FORCEPROP 1 LAST PACK_TYPE PIP
J 0
(-2950 5200);
PAINT SKYBLUE (-2950 5200);
DISPLAY INVISIBLE (-2950 5200);
FORCEPROP 2 LAST BOM_COST MEM
J 0
(-2500 3250);
PAINT ORANGE (-2500 3250);
DISPLAY INVISIBLE (-2500 3250);
FORCEPROP 2 LAST CDS_LIB mstr_sconn
J 0
(-2500 3250);
PAINT ORANGE (-2500 3250);
DISPLAY INVISIBLE (-2500 3250);
FORCEPROP 2 LAST SEC_TYPE PIP
J 0
(-2950 5200);
DISPLAY 1.021277 (-2950 5200);
PAINT ORANGE (-2950 5200);
DISPLAY INVISIBLE (-2950 5200);
FORCEPROP 2 LAST SEC 1
J 0
(-2950 5200);
DISPLAY 0.680851 (-2950 5200);
PAINT MONO (-2950 5200);
DISPLAY INVISIBLE (-2950 5200);
FORCEPROP 2 LAST CDS_LOCATION J1A1
J 0
(-2950 5150);
DISPLAY 0.617021 (-2950 5150);
PAINT AQUA (-2950 5150);
DISPLAY INVISIBLE (-2950 5150);
FORCEPROP 1 LAST PATH I186
J 0
(-2500 5100);
PAINT GREEN (-2500 5100);
DISPLAY INVISIBLE (-2500 5100);
FORCEPROP 2 LAST ROOM DDR4_CH_M
J 0
(-2500 3250);
PAINT ORANGE (-2500 3250);
DISPLAY INVISIBLE (-2500 3250);
FORCEADD SCONN288_H44441004..2
(0 4300);
FORCEPROP 1 LAST LOCATION J1A1
J 0
(-400 5400);
DISPLAY 0.617021 (-400 5400);
PAINT AQUA (-400 5400);
FORCEPROP 1 LAST PART_NUMBER H44441-004
J 0
(-400 3200);
DISPLAY 0.617021 (-400 3200);
PAINT BLUE (-400 3200);
FORCEPROP 1 LAST MATERIAL SCONN
J 0
(-400 5350);
DISPLAY 0.617021 (-400 5350);
PAINT SKYBLUE (-400 5350);
FORCEPROP 2 LASTPIN (450 5150) $PN 51
J 0
(460 5160);
DISPLAY 0.617021 (460 5160);
PAINT ORANGE (460 5160);
FORCEPROP 2 LASTPIN (450 5100) $PN 52
J 0
(460 5110);
DISPLAY 0.617021 (460 5110);
PAINT ORANGE (460 5110);
FORCEPROP 2 LASTPIN (450 5050) $PN 132
J 0
(460 5060);
DISPLAY 0.617021 (460 5060);
PAINT ORANGE (460 5060);
FORCEPROP 2 LASTPIN (450 5000) $PN 133
J 0
(460 5010);
DISPLAY 0.617021 (460 5010);
PAINT ORANGE (460 5010);
FORCEPROP 2 LASTPIN (450 4950) $PN 121
J 0
(460 4960);
DISPLAY 0.617021 (460 4960);
PAINT ORANGE (460 4960);
FORCEPROP 2 LASTPIN (450 4900) $PN 122
J 0
(460 4910);
DISPLAY 0.617021 (460 4910);
PAINT ORANGE (460 4910);
FORCEPROP 2 LASTPIN (450 4850) $PN 110
J 0
(460 4860);
DISPLAY 0.617021 (460 4860);
PAINT ORANGE (460 4860);
FORCEPROP 2 LASTPIN (450 4800) $PN 111
J 0
(460 4810);
DISPLAY 0.617021 (460 4810);
PAINT ORANGE (460 4810);
FORCEPROP 2 LASTPIN (450 4750) $PN 99
J 0
(460 4760);
DISPLAY 0.617021 (460 4760);
PAINT ORANGE (460 4760);
FORCEPROP 2 LASTPIN (450 4700) $PN 100
J 0
(460 4710);
DISPLAY 0.617021 (460 4710);
PAINT ORANGE (460 4710);
FORCEPROP 2 LASTPIN (450 4650) $PN 40
J 0
(460 4660);
DISPLAY 0.617021 (460 4660);
PAINT ORANGE (460 4660);
FORCEPROP 2 LASTPIN (450 4600) $PN 41
J 0
(460 4610);
DISPLAY 0.617021 (460 4610);
PAINT ORANGE (460 4610);
FORCEPROP 2 LASTPIN (450 4550) $PN 29
J 0
(460 4560);
DISPLAY 0.617021 (460 4560);
PAINT ORANGE (460 4560);
FORCEPROP 2 LASTPIN (450 4500) $PN 30
J 0
(460 4510);
DISPLAY 0.617021 (460 4510);
PAINT ORANGE (460 4510);
FORCEPROP 2 LASTPIN (450 4450) $PN 18
J 0
(460 4460);
DISPLAY 0.617021 (460 4460);
PAINT ORANGE (460 4460);
FORCEPROP 2 LASTPIN (450 4400) $PN 19
J 0
(460 4410);
DISPLAY 0.617021 (460 4410);
PAINT ORANGE (460 4410);
FORCEPROP 2 LASTPIN (450 4350) $PN 7
J 0
(460 4360);
DISPLAY 0.617021 (460 4360);
PAINT ORANGE (460 4360);
FORCEPROP 2 LASTPIN (450 4300) $PN 8
J 0
(460 4310);
DISPLAY 0.617021 (460 4310);
PAINT ORANGE (460 4310);
FORCEPROP 2 LASTPIN (450 4250) $PN 197
J 0
(460 4260);
DISPLAY 0.617021 (460 4260);
PAINT ORANGE (460 4260);
FORCEPROP 2 LASTPIN (450 4200) $PN 196
J 0
(460 4210);
DISPLAY 0.617021 (460 4210);
PAINT ORANGE (460 4210);
FORCEPROP 2 LASTPIN (450 4150) $PN 278
J 0
(460 4160);
DISPLAY 0.617021 (460 4160);
PAINT ORANGE (460 4160);
FORCEPROP 2 LASTPIN (450 4100) $PN 277
J 0
(460 4110);
DISPLAY 0.617021 (460 4110);
PAINT ORANGE (460 4110);
FORCEPROP 2 LASTPIN (450 4050) $PN 267
J 0
(460 4060);
DISPLAY 0.617021 (460 4060);
PAINT ORANGE (460 4060);
FORCEPROP 2 LASTPIN (450 4000) $PN 266
J 0
(460 4010);
DISPLAY 0.617021 (460 4010);
PAINT ORANGE (460 4010);
FORCEPROP 2 LASTPIN (450 3950) $PN 256
J 0
(460 3960);
DISPLAY 0.617021 (460 3960);
PAINT ORANGE (460 3960);
FORCEPROP 2 LASTPIN (450 3900) $PN 255
J 0
(460 3910);
DISPLAY 0.617021 (460 3910);
PAINT ORANGE (460 3910);
FORCEPROP 2 LASTPIN (450 3850) $PN 245
J 0
(460 3860);
DISPLAY 0.617021 (460 3860);
PAINT ORANGE (460 3860);
FORCEPROP 2 LASTPIN (450 3800) $PN 244
J 0
(460 3810);
DISPLAY 0.617021 (460 3810);
PAINT ORANGE (460 3810);
FORCEPROP 2 LASTPIN (450 3750) $PN 186
J 0
(460 3760);
DISPLAY 0.617021 (460 3760);
PAINT ORANGE (460 3760);
FORCEPROP 2 LASTPIN (450 3700) $PN 185
J 0
(460 3710);
DISPLAY 0.617021 (460 3710);
PAINT ORANGE (460 3710);
FORCEPROP 2 LASTPIN (450 3650) $PN 175
J 0
(460 3660);
DISPLAY 0.617021 (460 3660);
PAINT ORANGE (460 3660);
FORCEPROP 2 LASTPIN (450 3600) $PN 174
J 0
(460 3610);
DISPLAY 0.617021 (460 3610);
PAINT ORANGE (460 3610);
FORCEPROP 2 LASTPIN (450 3550) $PN 164
J 0
(460 3560);
DISPLAY 0.617021 (460 3560);
PAINT ORANGE (460 3560);
FORCEPROP 2 LASTPIN (450 3500) $PN 163
J 0
(460 3510);
DISPLAY 0.617021 (460 3510);
PAINT ORANGE (460 3510);
FORCEPROP 2 LASTPIN (450 3450) $PN 153
J 0
(460 3460);
DISPLAY 0.617021 (460 3460);
PAINT ORANGE (460 3460);
FORCEPROP 2 LASTPIN (450 3400) $PN 152
J 0
(460 3410);
DISPLAY 0.617021 (460 3410);
PAINT ORANGE (460 3410);
FORCEPROP 1 LAST PACK_TYPE PIP
J 0
(-400 5450);
PAINT SKYBLUE (-400 5450);
DISPLAY INVISIBLE (-400 5450);
FORCEPROP 2 LAST BOM_COST MEM
J 0
(0 4300);
PAINT ORANGE (0 4300);
DISPLAY INVISIBLE (0 4300);
FORCEPROP 2 LAST CDS_LIB mstr_sconn
J 0
(0 4300);
PAINT ORANGE (0 4300);
DISPLAY INVISIBLE (0 4300);
FORCEPROP 2 LAST SEC_TYPE PIP
J 0
(-400 5450);
DISPLAY 1.021277 (-400 5450);
PAINT ORANGE (-400 5450);
DISPLAY INVISIBLE (-400 5450);
FORCEPROP 2 LAST SEC 2
J 0
(-400 5450);
DISPLAY 0.680851 (-400 5450);
PAINT MONO (-400 5450);
DISPLAY INVISIBLE (-400 5450);
FORCEPROP 2 LAST CDS_LOCATION J1A1
J 0
(-400 5400);
DISPLAY 0.617021 (-400 5400);
PAINT AQUA (-400 5400);
DISPLAY INVISIBLE (-400 5400);
FORCEPROP 1 LAST PATH I187
J 0
(0 5350);
PAINT GREEN (0 5350);
DISPLAY INVISIBLE (0 5350);
FORCEPROP 2 LAST ROOM DDR4_CH_M
J 0
(0 4300);
PAINT ORANGE (0 4300);
DISPLAY INVISIBLE (0 4300);
FORCEADD P12V_NVDIMM_KLM..1
(300 3025);
FORCEPROP 3 LASTPIN (300 2975) SIG_NAME P12V_NVDIMM_KLM\g
J 0
(310 2985);
DISPLAY 0.659574 (310 2985);
PAINT MONO (310 2985);
DISPLAY INVISIBLE (310 2985);
FORCEPROP 1 LAST VOLTAGE 12.0
J 0
(255 2982);
DISPLAY 0.340426 (255 2982);
PAINT SKYBLUE (255 2982);
DISPLAY INVISIBLE (255 2982);
FORCEPROP 2 LAST CDS_LIB mstr_symbols
J 0
(300 3025);
PAINT ORANGE (300 3025);
DISPLAY INVISIBLE (300 3025);
FORCEPROP 1 LAST BODY_TYPE PLUMBING
J 0
(255 2982);
DISPLAY 0.340426 (255 2982);
PAINT GREEN (255 2982);
DISPLAY INVISIBLE (255 2982);
FORCEPROP 1 LAST PATH I188
J 0
(350 3050);
DISPLAY 0.872340 (350 3050);
PAINT AQUA (350 3050);
DISPLAY INVISIBLE (350 3050);
FORCEPROP 1 LAST HDL_POWER P12V_NVDIMM_KLM
J 1
(300 3075);
DISPLAY 0.872340 (300 3075);
PAINT GREEN (300 3075);
DISPLAY INVISIBLE (300 3075);
FORCEADD TAP..6
R 2
(900 3800);
FORCEPROP 3 LASTPIN (850 3800) SIG_NAME M_M_DQS_DN<4>
J 0
(860 3810);
DISPLAY 0.659574 (860 3810);
PAINT MONO (860 3810);
DISPLAY INVISIBLE (860 3810);
FORCEPROP 1 LASTPIN (850 3800) BN 4
J 2
(900 3810);
DISPLAY 0.617021 (900 3810);
PAINT PINK (900 3810);
FORCEPROP 2 LAST CDS_LIB mstr_standard
J 0
(900 3800);
DISPLAY 0.787234 (900 3800);
PAINT MONO (900 3800);
DISPLAY INVISIBLE (900 3800);
FORCEPROP 1 LAST BODY_TYPE PLUMBING
J 2
(900 3750);
DISPLAY 1.234043 (900 3750);
PAINT GREEN (900 3750);
DISPLAY INVISIBLE (900 3750);
FORCEPROP 1 LAST HDL_TAP TRUE
J 2
(575 3675);
DISPLAY 1.234043 (575 3675);
PAINT GREEN (575 3675);
DISPLAY INVISIBLE (575 3675);
FORCEPROP 1 LAST PATH I19
J 2
(900 3800);
DISPLAY 0.936170 (900 3800);
PAINT GREEN (900 3800);
DISPLAY INVISIBLE (900 3800);
FORCEADD OFFPAGE..3
(1600 5150);
FORCEPROP 2 LAST $XR0 62 
J 0
(1814 5150);
DISPLAY 0.638298 (1814 5150);
PAINT MONO (1814 5150);
FORCEPROP 2 LAST $XR1 88 
J 0
(1904 5150);
DISPLAY 0.638298 (1904 5150);
PAINT MONO (1904 5150);
FORCEPROP 2 LAST CDS_LIB mstr_standard
J 0
(1600 5150);
DISPLAY 0.787234 (1600 5150);
PAINT MONO (1600 5150);
DISPLAY INVISIBLE (1600 5150);
FORCEPROP 1 LAST OFFPAGE TRUE
J 0
(1925 5025);
DISPLAY 0.936170 (1925 5025);
PAINT GREEN (1925 5025);
DISPLAY INVISIBLE (1925 5025);
FORCEPROP 1 LAST COMMENT_BODY TRUE
J 0
(1550 5050);
DISPLAY 0.936170 (1550 5050);
PAINT GREEN (1550 5050);
DISPLAY INVISIBLE (1550 5050);
FORCEPROP 2 LAST PATH I2
J 0
(1800 5225);
DISPLAY 0.787234 (1800 5225);
PAINT MONO (1800 5225);
DISPLAY INVISIBLE (1800 5225);
FORCEADD TAP..6
R 2
(900 3700);
FORCEPROP 3 LASTPIN (850 3700) SIG_NAME M_M_DQS_DN<3>
J 0
(860 3710);
DISPLAY 0.659574 (860 3710);
PAINT MONO (860 3710);
DISPLAY INVISIBLE (860 3710);
FORCEPROP 1 LASTPIN (850 3700) BN 3
J 2
(900 3710);
DISPLAY 0.617021 (900 3710);
PAINT PINK (900 3710);
FORCEPROP 2 LAST CDS_LIB mstr_standard
J 0
(900 3700);
DISPLAY 0.787234 (900 3700);
PAINT MONO (900 3700);
DISPLAY INVISIBLE (900 3700);
FORCEPROP 1 LAST BODY_TYPE PLUMBING
J 2
(900 3650);
DISPLAY 1.234043 (900 3650);
PAINT GREEN (900 3650);
DISPLAY INVISIBLE (900 3650);
FORCEPROP 1 LAST HDL_TAP TRUE
J 2
(575 3575);
DISPLAY 1.234043 (575 3575);
PAINT GREEN (575 3575);
DISPLAY INVISIBLE (575 3575);
FORCEPROP 1 LAST PATH I20
J 2
(900 3700);
DISPLAY 0.936170 (900 3700);
PAINT GREEN (900 3700);
DISPLAY INVISIBLE (900 3700);
FORCEADD TAP..6
R 2
(900 3500);
FORCEPROP 3 LASTPIN (850 3500) SIG_NAME M_M_DQS_DN<1>
J 0
(860 3510);
DISPLAY 0.659574 (860 3510);
PAINT MONO (860 3510);
DISPLAY INVISIBLE (860 3510);
FORCEPROP 1 LASTPIN (850 3500) BN 1
J 2
(900 3510);
DISPLAY 0.617021 (900 3510);
PAINT PINK (900 3510);
FORCEPROP 2 LAST CDS_LIB mstr_standard
J 0
(900 3500);
DISPLAY 0.787234 (900 3500);
PAINT MONO (900 3500);
DISPLAY INVISIBLE (900 3500);
FORCEPROP 1 LAST BODY_TYPE PLUMBING
J 2
(900 3450);
DISPLAY 1.234043 (900 3450);
PAINT GREEN (900 3450);
DISPLAY INVISIBLE (900 3450);
FORCEPROP 1 LAST HDL_TAP TRUE
J 2
(575 3375);
DISPLAY 1.234043 (575 3375);
PAINT GREEN (575 3375);
DISPLAY INVISIBLE (575 3375);
FORCEPROP 1 LAST PATH I21
J 2
(900 3500);
DISPLAY 0.936170 (900 3500);
PAINT GREEN (900 3500);
DISPLAY INVISIBLE (900 3500);
FORCEADD TAP..6
R 2
(900 3600);
FORCEPROP 3 LASTPIN (850 3600) SIG_NAME M_M_DQS_DN<2>
J 0
(860 3610);
DISPLAY 0.659574 (860 3610);
PAINT MONO (860 3610);
DISPLAY INVISIBLE (860 3610);
FORCEPROP 1 LASTPIN (850 3600) BN 2
J 2
(900 3610);
DISPLAY 0.617021 (900 3610);
PAINT PINK (900 3610);
FORCEPROP 2 LAST CDS_LIB mstr_standard
J 0
(900 3600);
DISPLAY 0.787234 (900 3600);
PAINT MONO (900 3600);
DISPLAY INVISIBLE (900 3600);
FORCEPROP 1 LAST BODY_TYPE PLUMBING
J 2
(900 3550);
DISPLAY 1.234043 (900 3550);
PAINT GREEN (900 3550);
DISPLAY INVISIBLE (900 3550);
FORCEPROP 1 LAST HDL_TAP TRUE
J 2
(575 3475);
DISPLAY 1.234043 (575 3475);
PAINT GREEN (575 3475);
DISPLAY INVISIBLE (575 3475);
FORCEPROP 1 LAST PATH I22
J 2
(900 3600);
DISPLAY 0.936170 (900 3600);
PAINT GREEN (900 3600);
DISPLAY INVISIBLE (900 3600);
FORCEADD TAP..6
R 2
(900 3400);
FORCEPROP 3 LASTPIN (850 3400) SIG_NAME M_M_DQS_DN<0>
J 0
(860 3410);
DISPLAY 0.659574 (860 3410);
PAINT MONO (860 3410);
DISPLAY INVISIBLE (860 3410);
FORCEPROP 1 LASTPIN (850 3400) BN 0
J 2
(900 3410);
DISPLAY 0.617021 (900 3410);
PAINT PINK (900 3410);
FORCEPROP 2 LAST CDS_LIB mstr_standard
J 0
(900 3400);
DISPLAY 0.787234 (900 3400);
PAINT MONO (900 3400);
DISPLAY INVISIBLE (900 3400);
FORCEPROP 1 LAST BODY_TYPE PLUMBING
J 2
(900 3350);
DISPLAY 1.234043 (900 3350);
PAINT GREEN (900 3350);
DISPLAY INVISIBLE (900 3350);
FORCEPROP 1 LAST HDL_TAP TRUE
J 2
(575 3275);
DISPLAY 1.234043 (575 3275);
PAINT GREEN (575 3275);
DISPLAY INVISIBLE (575 3275);
FORCEPROP 1 LAST PATH I23
J 2
(900 3400);
DISPLAY 0.936170 (900 3400);
PAINT GREEN (900 3400);
DISPLAY INVISIBLE (900 3400);
FORCEADD GND..1
R 2
(1100 1150);
FORCEPROP 3 LASTPIN (1100 1200) SIG_NAME GND\g
J 0
(1110 1210);
DISPLAY 0.659574 (1110 1210);
PAINT MONO (1110 1210);
DISPLAY INVISIBLE (1110 1210);
FORCEPROP 1 LAST VOLTAGE 0
J 0
(1100 1150);
PAINT SKYBLUE (1100 1150);
DISPLAY INVISIBLE (1100 1150);
FORCEPROP 2 LAST BOM_COST MEM
J 0
(1100 1155);
PAINT ORANGE (1100 1155);
DISPLAY INVISIBLE (1100 1155);
FORCEPROP 1 LAST SIZE 1B
J 2
(1025 1100);
DISPLAY 1.170213 (1025 1100);
PAINT GREEN (1025 1100);
DISPLAY INVISIBLE (1025 1100);
FORCEPROP 2 LAST CDS_LIB mstr_symbols
J 0
(1100 1150);
DISPLAY 0.787234 (1100 1150);
PAINT MONO (1100 1150);
DISPLAY INVISIBLE (1100 1150);
FORCEPROP 1 LAST BODY_TYPE PLUMBING
J 2
(1145 1107);
DISPLAY 0.340426 (1145 1107);
PAINT GREEN (1145 1107);
DISPLAY INVISIBLE (1145 1107);
FORCEPROP 1 LAST PATH I26
J 2
(1025 1150);
DISPLAY 0.936170 (1025 1150);
PAINT GREEN (1025 1150);
DISPLAY INVISIBLE (1025 1150);
FORCEPROP 2 LAST ROOM DDR4_CH_D
J 0
(1100 1155);
PAINT ORANGE (1100 1155);
DISPLAY INVISIBLE (1100 1155);
FORCEPROP 1 LAST HDL_POWER GND
J 2
(1100 1300);
DISPLAY 0.553191 (1100 1300);
PAINT GREEN (1100 1300);
DISPLAY INVISIBLE (1100 1300);
FORCEADD TAP..6
R 2
(700 5150);
FORCEPROP 3 LASTPIN (650 5150) SIG_NAME M_M_DQS_DP<17>
J 0
(660 5160);
DISPLAY 0.659574 (660 5160);
PAINT MONO (660 5160);
DISPLAY INVISIBLE (660 5160);
FORCEPROP 1 LASTPIN (650 5150) BN 17
J 2
(700 5160);
DISPLAY 0.617021 (700 5160);
PAINT PINK (700 5160);
FORCEPROP 2 LAST CDS_LIB mstr_standard
J 2
(700 5150);
DISPLAY 0.787234 (700 5150);
PAINT MONO (700 5150);
DISPLAY INVISIBLE (700 5150);
FORCEPROP 1 LAST BODY_TYPE PLUMBING
J 2
(700 5100);
DISPLAY 1.234043 (700 5100);
PAINT GREEN (700 5100);
DISPLAY INVISIBLE (700 5100);
FORCEPROP 1 LAST HDL_TAP TRUE
J 2
(375 5025);
DISPLAY 1.234043 (375 5025);
PAINT GREEN (375 5025);
DISPLAY INVISIBLE (375 5025);
FORCEPROP 1 LAST PATH I27
J 2
(700 5150);
DISPLAY 0.936170 (700 5150);
PAINT GREEN (700 5150);
DISPLAY INVISIBLE (700 5150);
FORCEADD TAP..6
R 2
(700 5050);
FORCEPROP 3 LASTPIN (650 5050) SIG_NAME M_M_DQS_DP<16>
J 0
(660 5060);
DISPLAY 0.659574 (660 5060);
PAINT MONO (660 5060);
DISPLAY INVISIBLE (660 5060);
FORCEPROP 1 LASTPIN (650 5050) BN 16
J 2
(700 5060);
DISPLAY 0.617021 (700 5060);
PAINT PINK (700 5060);
FORCEPROP 2 LAST CDS_LIB mstr_standard
J 0
(700 5050);
DISPLAY 0.787234 (700 5050);
PAINT MONO (700 5050);
DISPLAY INVISIBLE (700 5050);
FORCEPROP 1 LAST BODY_TYPE PLUMBING
J 2
(700 5000);
DISPLAY 1.234043 (700 5000);
PAINT GREEN (700 5000);
DISPLAY INVISIBLE (700 5000);
FORCEPROP 1 LAST HDL_TAP TRUE
J 2
(375 4925);
DISPLAY 1.234043 (375 4925);
PAINT GREEN (375 4925);
DISPLAY INVISIBLE (375 4925);
FORCEPROP 1 LAST PATH I28
J 2
(700 5050);
DISPLAY 0.936170 (700 5050);
PAINT GREEN (700 5050);
DISPLAY INVISIBLE (700 5050);
FORCEADD TAP..6
R 2
(700 4750);
FORCEPROP 3 LASTPIN (650 4750) SIG_NAME M_M_DQS_DP<13>
J 0
(660 4760);
DISPLAY 0.659574 (660 4760);
PAINT MONO (660 4760);
DISPLAY INVISIBLE (660 4760);
FORCEPROP 1 LASTPIN (650 4750) BN 13
J 2
(700 4760);
DISPLAY 0.617021 (700 4760);
PAINT PINK (700 4760);
FORCEPROP 2 LAST CDS_LIB mstr_standard
J 0
(700 4750);
DISPLAY 0.787234 (700 4750);
PAINT MONO (700 4750);
DISPLAY INVISIBLE (700 4750);
FORCEPROP 1 LAST BODY_TYPE PLUMBING
J 2
(700 4700);
DISPLAY 1.234043 (700 4700);
PAINT GREEN (700 4700);
DISPLAY INVISIBLE (700 4700);
FORCEPROP 1 LAST HDL_TAP TRUE
J 2
(375 4625);
DISPLAY 1.234043 (375 4625);
PAINT GREEN (375 4625);
DISPLAY INVISIBLE (375 4625);
FORCEPROP 1 LAST PATH I29
J 2
(700 4750);
DISPLAY 0.936170 (700 4750);
PAINT GREEN (700 4750);
DISPLAY INVISIBLE (700 4750);
FORCEADD TAP..6
R 2
(900 5100);
FORCEPROP 3 LASTPIN (850 5100) SIG_NAME M_M_DQS_DN<17>
J 0
(860 5110);
DISPLAY 0.659574 (860 5110);
PAINT MONO (860 5110);
DISPLAY INVISIBLE (860 5110);
FORCEPROP 1 LASTPIN (850 5100) BN 17
J 2
(900 5110);
DISPLAY 0.617021 (900 5110);
PAINT PINK (900 5110);
FORCEPROP 2 LAST CDS_LIB mstr_standard
J 2
(900 5100);
DISPLAY 0.787234 (900 5100);
PAINT MONO (900 5100);
DISPLAY INVISIBLE (900 5100);
FORCEPROP 1 LAST BODY_TYPE PLUMBING
J 2
(900 5050);
DISPLAY 1.234043 (900 5050);
PAINT GREEN (900 5050);
DISPLAY INVISIBLE (900 5050);
FORCEPROP 1 LAST HDL_TAP TRUE
J 2
(575 4975);
DISPLAY 1.234043 (575 4975);
PAINT GREEN (575 4975);
DISPLAY INVISIBLE (575 4975);
FORCEPROP 1 LAST PATH I3
J 2
(900 5100);
DISPLAY 0.936170 (900 5100);
PAINT GREEN (900 5100);
DISPLAY INVISIBLE (900 5100);
FORCEADD TAP..6
R 2
(700 4650);
FORCEPROP 3 LASTPIN (650 4650) SIG_NAME M_M_DQS_DP<12>
J 0
(660 4660);
DISPLAY 0.659574 (660 4660);
PAINT MONO (660 4660);
DISPLAY INVISIBLE (660 4660);
FORCEPROP 1 LASTPIN (650 4650) BN 12
J 2
(700 4660);
DISPLAY 0.617021 (700 4660);
PAINT PINK (700 4660);
FORCEPROP 2 LAST CDS_LIB mstr_standard
J 0
(700 4650);
DISPLAY 0.787234 (700 4650);
PAINT MONO (700 4650);
DISPLAY INVISIBLE (700 4650);
FORCEPROP 1 LAST BODY_TYPE PLUMBING
J 2
(700 4600);
DISPLAY 1.234043 (700 4600);
PAINT GREEN (700 4600);
DISPLAY INVISIBLE (700 4600);
FORCEPROP 1 LAST HDL_TAP TRUE
J 2
(375 4525);
DISPLAY 1.234043 (375 4525);
PAINT GREEN (375 4525);
DISPLAY INVISIBLE (375 4525);
FORCEPROP 1 LAST PATH I30
J 2
(700 4650);
DISPLAY 0.936170 (700 4650);
PAINT GREEN (700 4650);
DISPLAY INVISIBLE (700 4650);
FORCEADD TAP..6
R 2
(700 4550);
FORCEPROP 3 LASTPIN (650 4550) SIG_NAME M_M_DQS_DP<11>
J 0
(660 4560);
DISPLAY 0.659574 (660 4560);
PAINT MONO (660 4560);
DISPLAY INVISIBLE (660 4560);
FORCEPROP 1 LASTPIN (650 4550) BN 11
J 2
(700 4560);
DISPLAY 0.617021 (700 4560);
PAINT PINK (700 4560);
FORCEPROP 2 LAST CDS_LIB mstr_standard
J 0
(700 4550);
DISPLAY 0.787234 (700 4550);
PAINT MONO (700 4550);
DISPLAY INVISIBLE (700 4550);
FORCEPROP 1 LAST BODY_TYPE PLUMBING
J 2
(700 4500);
DISPLAY 1.234043 (700 4500);
PAINT GREEN (700 4500);
DISPLAY INVISIBLE (700 4500);
FORCEPROP 1 LAST HDL_TAP TRUE
J 2
(375 4425);
DISPLAY 1.234043 (375 4425);
PAINT GREEN (375 4425);
DISPLAY INVISIBLE (375 4425);
FORCEPROP 1 LAST PATH I31
J 2
(700 4550);
DISPLAY 0.936170 (700 4550);
PAINT GREEN (700 4550);
DISPLAY INVISIBLE (700 4550);
FORCEADD TAP..6
R 2
(700 4950);
FORCEPROP 3 LASTPIN (650 4950) SIG_NAME M_M_DQS_DP<15>
J 0
(660 4960);
DISPLAY 0.659574 (660 4960);
PAINT MONO (660 4960);
DISPLAY INVISIBLE (660 4960);
FORCEPROP 1 LASTPIN (650 4950) BN 15
J 2
(700 4960);
DISPLAY 0.617021 (700 4960);
PAINT PINK (700 4960);
FORCEPROP 2 LAST CDS_LIB mstr_standard
J 0
(700 4950);
DISPLAY 0.787234 (700 4950);
PAINT MONO (700 4950);
DISPLAY INVISIBLE (700 4950);
FORCEPROP 1 LAST BODY_TYPE PLUMBING
J 2
(700 4900);
DISPLAY 1.234043 (700 4900);
PAINT GREEN (700 4900);
DISPLAY INVISIBLE (700 4900);
FORCEPROP 1 LAST HDL_TAP TRUE
J 2
(375 4825);
DISPLAY 1.234043 (375 4825);
PAINT GREEN (375 4825);
DISPLAY INVISIBLE (375 4825);
FORCEPROP 1 LAST PATH I32
J 2
(700 4950);
DISPLAY 0.936170 (700 4950);
PAINT GREEN (700 4950);
DISPLAY INVISIBLE (700 4950);
FORCEADD TAP..6
R 2
(700 4850);
FORCEPROP 3 LASTPIN (650 4850) SIG_NAME M_M_DQS_DP<14>
J 0
(660 4860);
DISPLAY 0.659574 (660 4860);
PAINT MONO (660 4860);
DISPLAY INVISIBLE (660 4860);
FORCEPROP 1 LASTPIN (650 4850) BN 14
J 2
(700 4860);
DISPLAY 0.617021 (700 4860);
PAINT PINK (700 4860);
FORCEPROP 2 LAST CDS_LIB mstr_standard
J 0
(700 4850);
DISPLAY 0.787234 (700 4850);
PAINT MONO (700 4850);
DISPLAY INVISIBLE (700 4850);
FORCEPROP 1 LAST BODY_TYPE PLUMBING
J 2
(700 4800);
DISPLAY 1.234043 (700 4800);
PAINT GREEN (700 4800);
DISPLAY INVISIBLE (700 4800);
FORCEPROP 1 LAST HDL_TAP TRUE
J 2
(375 4725);
DISPLAY 1.234043 (375 4725);
PAINT GREEN (375 4725);
DISPLAY INVISIBLE (375 4725);
FORCEPROP 1 LAST PATH I33
J 2
(700 4850);
DISPLAY 0.936170 (700 4850);
PAINT GREEN (700 4850);
DISPLAY INVISIBLE (700 4850);
FORCEADD OFFPAGE..3
(-1200 4950);
FORCEPROP 2 LAST $XR0 62 
J 0
(-986 4950);
DISPLAY 0.638298 (-986 4950);
PAINT MONO (-986 4950);
FORCEPROP 2 LAST $XR1 88 
J 0
(-896 4950);
DISPLAY 0.638298 (-896 4950);
PAINT MONO (-896 4950);
FORCEPROP 2 LAST CDS_LIB mstr_standard
J 0
(-1200 4950);
DISPLAY 0.787234 (-1200 4950);
PAINT MONO (-1200 4950);
DISPLAY INVISIBLE (-1200 4950);
FORCEPROP 1 LAST OFFPAGE TRUE
J 0
(-875 4825);
DISPLAY 0.936170 (-875 4825);
PAINT GREEN (-875 4825);
DISPLAY INVISIBLE (-875 4825);
FORCEPROP 1 LAST COMMENT_BODY TRUE
J 0
(-1250 4850);
DISPLAY 0.936170 (-1250 4850);
PAINT GREEN (-1250 4850);
DISPLAY INVISIBLE (-1250 4850);
FORCEPROP 2 LAST PATH I34
J 0
(-1000 5025);
DISPLAY 0.787234 (-1000 5025);
PAINT MONO (-1000 5025);
DISPLAY INVISIBLE (-1000 5025);
FORCEADD TAP..6
R 2
(-1750 4700);
FORCEPROP 3 LASTPIN (-1800 4700) SIG_NAME M_M_DQ<58>
J 0
(-1790 4710);
DISPLAY 0.659574 (-1790 4710);
PAINT MONO (-1790 4710);
DISPLAY INVISIBLE (-1790 4710);
FORCEPROP 1 LASTPIN (-1800 4700) BN 58
J 2
(-1750 4710);
DISPLAY 0.617021 (-1750 4710);
PAINT PINK (-1750 4710);
FORCEPROP 2 LAST CDS_LIB mstr_standard
J 2
(-1750 4700);
DISPLAY 0.787234 (-1750 4700);
PAINT MONO (-1750 4700);
DISPLAY INVISIBLE (-1750 4700);
FORCEPROP 1 LAST BODY_TYPE PLUMBING
J 2
(-1750 4650);
DISPLAY 1.234043 (-1750 4650);
PAINT GREEN (-1750 4650);
DISPLAY INVISIBLE (-1750 4650);
FORCEPROP 1 LAST HDL_TAP TRUE
J 2
(-2075 4575);
DISPLAY 1.234043 (-2075 4575);
PAINT GREEN (-2075 4575);
DISPLAY INVISIBLE (-2075 4575);
FORCEPROP 1 LAST PATH I35
J 2
(-1750 4700);
DISPLAY 0.936170 (-1750 4700);
PAINT GREEN (-1750 4700);
DISPLAY INVISIBLE (-1750 4700);
FORCEADD TAP..6
R 2
(-1750 4900);
FORCEPROP 3 LASTPIN (-1800 4900) SIG_NAME M_M_DQ<62>
J 0
(-1790 4910);
DISPLAY 0.659574 (-1790 4910);
PAINT MONO (-1790 4910);
DISPLAY INVISIBLE (-1790 4910);
FORCEPROP 1 LASTPIN (-1800 4900) BN 62
J 2
(-1750 4910);
DISPLAY 0.617021 (-1750 4910);
PAINT PINK (-1750 4910);
FORCEPROP 2 LAST CDS_LIB mstr_standard
J 2
(-1750 4900);
DISPLAY 0.787234 (-1750 4900);
PAINT MONO (-1750 4900);
DISPLAY INVISIBLE (-1750 4900);
FORCEPROP 1 LAST BODY_TYPE PLUMBING
J 2
(-1750 4850);
DISPLAY 1.234043 (-1750 4850);
PAINT GREEN (-1750 4850);
DISPLAY INVISIBLE (-1750 4850);
FORCEPROP 1 LAST HDL_TAP TRUE
J 2
(-2075 4775);
DISPLAY 1.234043 (-2075 4775);
PAINT GREEN (-2075 4775);
DISPLAY INVISIBLE (-2075 4775);
FORCEPROP 1 LAST PATH I36
J 2
(-1750 4900);
DISPLAY 0.936170 (-1750 4900);
PAINT GREEN (-1750 4900);
DISPLAY INVISIBLE (-1750 4900);
FORCEADD TAP..6
R 2
(-1750 4850);
FORCEPROP 3 LASTPIN (-1800 4850) SIG_NAME M_M_DQ<63>
J 0
(-1790 4860);
DISPLAY 0.659574 (-1790 4860);
PAINT MONO (-1790 4860);
DISPLAY INVISIBLE (-1790 4860);
FORCEPROP 1 LASTPIN (-1800 4850) BN 63
J 2
(-1750 4860);
DISPLAY 0.617021 (-1750 4860);
PAINT PINK (-1750 4860);
FORCEPROP 2 LAST CDS_LIB mstr_standard
J 2
(-1750 4850);
DISPLAY 0.787234 (-1750 4850);
PAINT MONO (-1750 4850);
DISPLAY INVISIBLE (-1750 4850);
FORCEPROP 1 LAST BODY_TYPE PLUMBING
J 2
(-1750 4800);
DISPLAY 1.234043 (-1750 4800);
PAINT GREEN (-1750 4800);
DISPLAY INVISIBLE (-1750 4800);
FORCEPROP 1 LAST HDL_TAP TRUE
J 2
(-2075 4725);
DISPLAY 1.234043 (-2075 4725);
PAINT GREEN (-2075 4725);
DISPLAY INVISIBLE (-2075 4725);
FORCEPROP 1 LAST PATH I37
J 2
(-1750 4850);
DISPLAY 0.936170 (-1750 4850);
PAINT GREEN (-1750 4850);
DISPLAY INVISIBLE (-1750 4850);
FORCEADD TAP..6
R 2
(-1750 4800);
FORCEPROP 3 LASTPIN (-1800 4800) SIG_NAME M_M_DQ<60>
J 0
(-1790 4810);
DISPLAY 0.659574 (-1790 4810);
PAINT MONO (-1790 4810);
DISPLAY INVISIBLE (-1790 4810);
FORCEPROP 1 LASTPIN (-1800 4800) BN 60
J 2
(-1750 4810);
DISPLAY 0.617021 (-1750 4810);
PAINT PINK (-1750 4810);
FORCEPROP 2 LAST CDS_LIB mstr_standard
J 2
(-1750 4800);
DISPLAY 0.787234 (-1750 4800);
PAINT MONO (-1750 4800);
DISPLAY INVISIBLE (-1750 4800);
FORCEPROP 1 LAST BODY_TYPE PLUMBING
J 2
(-1750 4750);
DISPLAY 1.234043 (-1750 4750);
PAINT GREEN (-1750 4750);
DISPLAY INVISIBLE (-1750 4750);
FORCEPROP 1 LAST HDL_TAP TRUE
J 2
(-2075 4675);
DISPLAY 1.234043 (-2075 4675);
PAINT GREEN (-2075 4675);
DISPLAY INVISIBLE (-2075 4675);
FORCEPROP 1 LAST PATH I38
J 2
(-1750 4800);
DISPLAY 0.936170 (-1750 4800);
PAINT GREEN (-1750 4800);
DISPLAY INVISIBLE (-1750 4800);
FORCEADD TAP..6
R 2
(-1750 4750);
FORCEPROP 3 LASTPIN (-1800 4750) SIG_NAME M_M_DQ<61>
J 0
(-1790 4760);
DISPLAY 0.659574 (-1790 4760);
PAINT MONO (-1790 4760);
DISPLAY INVISIBLE (-1790 4760);
FORCEPROP 1 LASTPIN (-1800 4750) BN 61
J 2
(-1750 4760);
DISPLAY 0.617021 (-1750 4760);
PAINT PINK (-1750 4760);
FORCEPROP 2 LAST CDS_LIB mstr_standard
J 2
(-1750 4750);
DISPLAY 0.787234 (-1750 4750);
PAINT MONO (-1750 4750);
DISPLAY INVISIBLE (-1750 4750);
FORCEPROP 1 LAST BODY_TYPE PLUMBING
J 2
(-1750 4700);
DISPLAY 1.234043 (-1750 4700);
PAINT GREEN (-1750 4700);
DISPLAY INVISIBLE (-1750 4700);
FORCEPROP 1 LAST HDL_TAP TRUE
J 2
(-2075 4625);
DISPLAY 1.234043 (-2075 4625);
PAINT GREEN (-2075 4625);
DISPLAY INVISIBLE (-2075 4625);
FORCEPROP 1 LAST PATH I39
J 2
(-1750 4750);
DISPLAY 0.936170 (-1750 4750);
PAINT GREEN (-1750 4750);
DISPLAY INVISIBLE (-1750 4750);
FORCEADD TAP..6
R 2
(900 5000);
FORCEPROP 3 LASTPIN (850 5000) SIG_NAME M_M_DQS_DN<16>
J 0
(860 5010);
DISPLAY 0.659574 (860 5010);
PAINT MONO (860 5010);
DISPLAY INVISIBLE (860 5010);
FORCEPROP 1 LASTPIN (850 5000) BN 16
J 2
(900 5010);
DISPLAY 0.617021 (900 5010);
PAINT PINK (900 5010);
FORCEPROP 2 LAST CDS_LIB mstr_standard
J 0
(900 5000);
DISPLAY 0.787234 (900 5000);
PAINT MONO (900 5000);
DISPLAY INVISIBLE (900 5000);
FORCEPROP 1 LAST BODY_TYPE PLUMBING
J 2
(900 4950);
DISPLAY 1.234043 (900 4950);
PAINT GREEN (900 4950);
DISPLAY INVISIBLE (900 4950);
FORCEPROP 1 LAST HDL_TAP TRUE
J 2
(575 4875);
DISPLAY 1.234043 (575 4875);
PAINT GREEN (575 4875);
DISPLAY INVISIBLE (575 4875);
FORCEPROP 1 LAST PATH I4
J 2
(900 5000);
DISPLAY 0.936170 (900 5000);
PAINT GREEN (900 5000);
DISPLAY INVISIBLE (900 5000);
FORCEADD TAP..6
R 2
(-1750 4450);
FORCEPROP 3 LASTPIN (-1800 4450) SIG_NAME M_M_DQ<55>
J 0
(-1790 4460);
DISPLAY 0.659574 (-1790 4460);
PAINT MONO (-1790 4460);
DISPLAY INVISIBLE (-1790 4460);
FORCEPROP 1 LASTPIN (-1800 4450) BN 55
J 2
(-1750 4460);
DISPLAY 0.617021 (-1750 4460);
PAINT PINK (-1750 4460);
FORCEPROP 2 LAST CDS_LIB mstr_standard
J 2
(-1750 4450);
DISPLAY 0.787234 (-1750 4450);
PAINT MONO (-1750 4450);
DISPLAY INVISIBLE (-1750 4450);
FORCEPROP 1 LAST BODY_TYPE PLUMBING
J 2
(-1750 4400);
DISPLAY 1.234043 (-1750 4400);
PAINT GREEN (-1750 4400);
DISPLAY INVISIBLE (-1750 4400);
FORCEPROP 1 LAST HDL_TAP TRUE
J 2
(-2075 4325);
DISPLAY 1.234043 (-2075 4325);
PAINT GREEN (-2075 4325);
DISPLAY INVISIBLE (-2075 4325);
FORCEPROP 1 LAST PATH I40
J 2
(-1750 4450);
DISPLAY 0.936170 (-1750 4450);
PAINT GREEN (-1750 4450);
DISPLAY INVISIBLE (-1750 4450);
FORCEADD TAP..6
R 2
(-1750 4600);
FORCEPROP 3 LASTPIN (-1800 4600) SIG_NAME M_M_DQ<56>
J 0
(-1790 4610);
DISPLAY 0.659574 (-1790 4610);
PAINT MONO (-1790 4610);
DISPLAY INVISIBLE (-1790 4610);
FORCEPROP 1 LASTPIN (-1800 4600) BN 56
J 2
(-1750 4610);
DISPLAY 0.617021 (-1750 4610);
PAINT PINK (-1750 4610);
FORCEPROP 2 LAST CDS_LIB mstr_standard
J 2
(-1750 4600);
DISPLAY 0.787234 (-1750 4600);
PAINT MONO (-1750 4600);
DISPLAY INVISIBLE (-1750 4600);
FORCEPROP 1 LAST BODY_TYPE PLUMBING
J 2
(-1750 4550);
DISPLAY 1.234043 (-1750 4550);
PAINT GREEN (-1750 4550);
DISPLAY INVISIBLE (-1750 4550);
FORCEPROP 1 LAST HDL_TAP TRUE
J 2
(-2075 4475);
DISPLAY 1.234043 (-2075 4475);
PAINT GREEN (-2075 4475);
DISPLAY INVISIBLE (-2075 4475);
FORCEPROP 1 LAST PATH I41
J 2
(-1750 4600);
DISPLAY 0.936170 (-1750 4600);
PAINT GREEN (-1750 4600);
DISPLAY INVISIBLE (-1750 4600);
FORCEADD TAP..6
R 2
(-1750 4650);
FORCEPROP 3 LASTPIN (-1800 4650) SIG_NAME M_M_DQ<59>
J 0
(-1790 4660);
DISPLAY 0.659574 (-1790 4660);
PAINT MONO (-1790 4660);
DISPLAY INVISIBLE (-1790 4660);
FORCEPROP 1 LASTPIN (-1800 4650) BN 59
J 2
(-1750 4660);
DISPLAY 0.617021 (-1750 4660);
PAINT PINK (-1750 4660);
FORCEPROP 2 LAST CDS_LIB mstr_standard
J 2
(-1750 4650);
DISPLAY 0.787234 (-1750 4650);
PAINT MONO (-1750 4650);
DISPLAY INVISIBLE (-1750 4650);
FORCEPROP 1 LAST BODY_TYPE PLUMBING
J 2
(-1750 4600);
DISPLAY 1.234043 (-1750 4600);
PAINT GREEN (-1750 4600);
DISPLAY INVISIBLE (-1750 4600);
FORCEPROP 1 LAST HDL_TAP TRUE
J 2
(-2075 4525);
DISPLAY 1.234043 (-2075 4525);
PAINT GREEN (-2075 4525);
DISPLAY INVISIBLE (-2075 4525);
FORCEPROP 1 LAST PATH I42
J 2
(-1750 4650);
DISPLAY 0.936170 (-1750 4650);
PAINT GREEN (-1750 4650);
DISPLAY INVISIBLE (-1750 4650);
FORCEADD TAP..6
R 2
(-1750 4500);
FORCEPROP 3 LASTPIN (-1800 4500) SIG_NAME M_M_DQ<54>
J 0
(-1790 4510);
DISPLAY 0.659574 (-1790 4510);
PAINT MONO (-1790 4510);
DISPLAY INVISIBLE (-1790 4510);
FORCEPROP 1 LASTPIN (-1800 4500) BN 54
J 2
(-1750 4510);
DISPLAY 0.617021 (-1750 4510);
PAINT PINK (-1750 4510);
FORCEPROP 2 LAST CDS_LIB mstr_standard
J 2
(-1750 4500);
DISPLAY 0.787234 (-1750 4500);
PAINT MONO (-1750 4500);
DISPLAY INVISIBLE (-1750 4500);
FORCEPROP 1 LAST BODY_TYPE PLUMBING
J 2
(-1750 4450);
DISPLAY 1.234043 (-1750 4450);
PAINT GREEN (-1750 4450);
DISPLAY INVISIBLE (-1750 4450);
FORCEPROP 1 LAST HDL_TAP TRUE
J 2
(-2075 4375);
DISPLAY 1.234043 (-2075 4375);
PAINT GREEN (-2075 4375);
DISPLAY INVISIBLE (-2075 4375);
FORCEPROP 1 LAST PATH I43
J 2
(-1750 4500);
DISPLAY 0.936170 (-1750 4500);
PAINT GREEN (-1750 4500);
DISPLAY INVISIBLE (-1750 4500);
FORCEADD TAP..6
R 2
(-1750 4550);
FORCEPROP 3 LASTPIN (-1800 4550) SIG_NAME M_M_DQ<57>
J 0
(-1790 4560);
DISPLAY 0.659574 (-1790 4560);
PAINT MONO (-1790 4560);
DISPLAY INVISIBLE (-1790 4560);
FORCEPROP 1 LASTPIN (-1800 4550) BN 57
J 2
(-1750 4560);
DISPLAY 0.617021 (-1750 4560);
PAINT PINK (-1750 4560);
FORCEPROP 2 LAST CDS_LIB mstr_standard
J 2
(-1750 4550);
DISPLAY 0.787234 (-1750 4550);
PAINT MONO (-1750 4550);
DISPLAY INVISIBLE (-1750 4550);
FORCEPROP 1 LAST BODY_TYPE PLUMBING
J 2
(-1750 4500);
DISPLAY 1.234043 (-1750 4500);
PAINT GREEN (-1750 4500);
DISPLAY INVISIBLE (-1750 4500);
FORCEPROP 1 LAST HDL_TAP TRUE
J 2
(-2075 4425);
DISPLAY 1.234043 (-2075 4425);
PAINT GREEN (-2075 4425);
DISPLAY INVISIBLE (-2075 4425);
FORCEPROP 1 LAST PATH I44
J 2
(-1750 4550);
DISPLAY 0.936170 (-1750 4550);
PAINT GREEN (-1750 4550);
DISPLAY INVISIBLE (-1750 4550);
FORCEADD TAP..6
R 2
(-1750 4200);
FORCEPROP 3 LASTPIN (-1800 4200) SIG_NAME M_M_DQ<48>
J 0
(-1790 4210);
DISPLAY 0.659574 (-1790 4210);
PAINT MONO (-1790 4210);
DISPLAY INVISIBLE (-1790 4210);
FORCEPROP 1 LASTPIN (-1800 4200) BN 48
J 2
(-1750 4210);
DISPLAY 0.617021 (-1750 4210);
PAINT PINK (-1750 4210);
FORCEPROP 2 LAST CDS_LIB mstr_standard
J 2
(-1750 4200);
DISPLAY 0.787234 (-1750 4200);
PAINT MONO (-1750 4200);
DISPLAY INVISIBLE (-1750 4200);
FORCEPROP 1 LAST BODY_TYPE PLUMBING
J 2
(-1750 4150);
DISPLAY 1.234043 (-1750 4150);
PAINT GREEN (-1750 4150);
DISPLAY INVISIBLE (-1750 4150);
FORCEPROP 1 LAST HDL_TAP TRUE
J 2
(-2075 4075);
DISPLAY 1.234043 (-2075 4075);
PAINT GREEN (-2075 4075);
DISPLAY INVISIBLE (-2075 4075);
FORCEPROP 1 LAST PATH I45
J 2
(-1750 4200);
DISPLAY 0.936170 (-1750 4200);
PAINT GREEN (-1750 4200);
DISPLAY INVISIBLE (-1750 4200);
FORCEADD TAP..6
R 2
(-1750 4400);
FORCEPROP 3 LASTPIN (-1800 4400) SIG_NAME M_M_DQ<52>
J 0
(-1790 4410);
DISPLAY 0.659574 (-1790 4410);
PAINT MONO (-1790 4410);
DISPLAY INVISIBLE (-1790 4410);
FORCEPROP 1 LASTPIN (-1800 4400) BN 52
J 2
(-1750 4410);
DISPLAY 0.617021 (-1750 4410);
PAINT PINK (-1750 4410);
FORCEPROP 2 LAST CDS_LIB mstr_standard
J 2
(-1750 4400);
DISPLAY 0.787234 (-1750 4400);
PAINT MONO (-1750 4400);
DISPLAY INVISIBLE (-1750 4400);
FORCEPROP 1 LAST BODY_TYPE PLUMBING
J 2
(-1750 4350);
DISPLAY 1.234043 (-1750 4350);
PAINT GREEN (-1750 4350);
DISPLAY INVISIBLE (-1750 4350);
FORCEPROP 1 LAST HDL_TAP TRUE
J 2
(-2075 4275);
DISPLAY 1.234043 (-2075 4275);
PAINT GREEN (-2075 4275);
DISPLAY INVISIBLE (-2075 4275);
FORCEPROP 1 LAST PATH I46
J 2
(-1750 4400);
DISPLAY 0.936170 (-1750 4400);
PAINT GREEN (-1750 4400);
DISPLAY INVISIBLE (-1750 4400);
FORCEADD TAP..6
R 2
(-1750 4350);
FORCEPROP 3 LASTPIN (-1800 4350) SIG_NAME M_M_DQ<53>
J 0
(-1790 4360);
DISPLAY 0.659574 (-1790 4360);
PAINT MONO (-1790 4360);
DISPLAY INVISIBLE (-1790 4360);
FORCEPROP 1 LASTPIN (-1800 4350) BN 53
J 2
(-1750 4360);
DISPLAY 0.617021 (-1750 4360);
PAINT PINK (-1750 4360);
FORCEPROP 2 LAST CDS_LIB mstr_standard
J 2
(-1750 4350);
DISPLAY 0.787234 (-1750 4350);
PAINT MONO (-1750 4350);
DISPLAY INVISIBLE (-1750 4350);
FORCEPROP 1 LAST BODY_TYPE PLUMBING
J 2
(-1750 4300);
DISPLAY 1.234043 (-1750 4300);
PAINT GREEN (-1750 4300);
DISPLAY INVISIBLE (-1750 4300);
FORCEPROP 1 LAST HDL_TAP TRUE
J 2
(-2075 4225);
DISPLAY 1.234043 (-2075 4225);
PAINT GREEN (-2075 4225);
DISPLAY INVISIBLE (-2075 4225);
FORCEPROP 1 LAST PATH I47
J 2
(-1750 4350);
DISPLAY 0.936170 (-1750 4350);
PAINT GREEN (-1750 4350);
DISPLAY INVISIBLE (-1750 4350);
FORCEADD TAP..6
R 2
(-1750 4250);
FORCEPROP 3 LASTPIN (-1800 4250) SIG_NAME M_M_DQ<51>
J 0
(-1790 4260);
DISPLAY 0.659574 (-1790 4260);
PAINT MONO (-1790 4260);
DISPLAY INVISIBLE (-1790 4260);
FORCEPROP 1 LASTPIN (-1800 4250) BN 51
J 2
(-1750 4260);
DISPLAY 0.617021 (-1750 4260);
PAINT PINK (-1750 4260);
FORCEPROP 2 LAST CDS_LIB mstr_standard
J 2
(-1750 4250);
DISPLAY 0.787234 (-1750 4250);
PAINT MONO (-1750 4250);
DISPLAY INVISIBLE (-1750 4250);
FORCEPROP 1 LAST BODY_TYPE PLUMBING
J 2
(-1750 4200);
DISPLAY 1.234043 (-1750 4200);
PAINT GREEN (-1750 4200);
DISPLAY INVISIBLE (-1750 4200);
FORCEPROP 1 LAST HDL_TAP TRUE
J 2
(-2075 4125);
DISPLAY 1.234043 (-2075 4125);
PAINT GREEN (-2075 4125);
DISPLAY INVISIBLE (-2075 4125);
FORCEPROP 1 LAST PATH I48
J 2
(-1750 4250);
DISPLAY 0.936170 (-1750 4250);
PAINT GREEN (-1750 4250);
DISPLAY INVISIBLE (-1750 4250);
FORCEADD TAP..6
R 2
(-1750 4300);
FORCEPROP 3 LASTPIN (-1800 4300) SIG_NAME M_M_DQ<50>
J 0
(-1790 4310);
DISPLAY 0.659574 (-1790 4310);
PAINT MONO (-1790 4310);
DISPLAY INVISIBLE (-1790 4310);
FORCEPROP 1 LASTPIN (-1800 4300) BN 50
J 2
(-1750 4310);
DISPLAY 0.617021 (-1750 4310);
PAINT PINK (-1750 4310);
FORCEPROP 2 LAST CDS_LIB mstr_standard
J 2
(-1750 4300);
DISPLAY 0.787234 (-1750 4300);
PAINT MONO (-1750 4300);
DISPLAY INVISIBLE (-1750 4300);
FORCEPROP 1 LAST BODY_TYPE PLUMBING
J 2
(-1750 4250);
DISPLAY 1.234043 (-1750 4250);
PAINT GREEN (-1750 4250);
DISPLAY INVISIBLE (-1750 4250);
FORCEPROP 1 LAST HDL_TAP TRUE
J 2
(-2075 4175);
DISPLAY 1.234043 (-2075 4175);
PAINT GREEN (-2075 4175);
DISPLAY INVISIBLE (-2075 4175);
FORCEPROP 1 LAST PATH I49
J 2
(-1750 4300);
DISPLAY 0.936170 (-1750 4300);
PAINT GREEN (-1750 4300);
DISPLAY INVISIBLE (-1750 4300);
FORCEADD TAP..6
R 2
(900 4900);
FORCEPROP 3 LASTPIN (850 4900) SIG_NAME M_M_DQS_DN<15>
J 0
(860 4910);
DISPLAY 0.659574 (860 4910);
PAINT MONO (860 4910);
DISPLAY INVISIBLE (860 4910);
FORCEPROP 1 LASTPIN (850 4900) BN 15
J 2
(900 4910);
DISPLAY 0.617021 (900 4910);
PAINT PINK (900 4910);
FORCEPROP 2 LAST CDS_LIB mstr_standard
J 0
(900 4900);
DISPLAY 0.787234 (900 4900);
PAINT MONO (900 4900);
DISPLAY INVISIBLE (900 4900);
FORCEPROP 1 LAST BODY_TYPE PLUMBING
J 2
(900 4850);
DISPLAY 1.234043 (900 4850);
PAINT GREEN (900 4850);
DISPLAY INVISIBLE (900 4850);
FORCEPROP 1 LAST HDL_TAP TRUE
J 2
(575 4775);
DISPLAY 1.234043 (575 4775);
PAINT GREEN (575 4775);
DISPLAY INVISIBLE (575 4775);
FORCEPROP 1 LAST PATH I5
J 2
(900 4900);
DISPLAY 0.936170 (900 4900);
PAINT GREEN (900 4900);
DISPLAY INVISIBLE (900 4900);
FORCEADD TAP..6
R 2
(-1750 4100);
FORCEPROP 3 LASTPIN (-1800 4100) SIG_NAME M_M_DQ<46>
J 0
(-1790 4110);
DISPLAY 0.659574 (-1790 4110);
PAINT MONO (-1790 4110);
DISPLAY INVISIBLE (-1790 4110);
FORCEPROP 1 LASTPIN (-1800 4100) BN 46
J 2
(-1750 4110);
DISPLAY 0.617021 (-1750 4110);
PAINT PINK (-1750 4110);
FORCEPROP 2 LAST CDS_LIB mstr_standard
J 2
(-1750 4100);
DISPLAY 0.787234 (-1750 4100);
PAINT MONO (-1750 4100);
DISPLAY INVISIBLE (-1750 4100);
FORCEPROP 1 LAST BODY_TYPE PLUMBING
J 2
(-1750 4050);
DISPLAY 1.234043 (-1750 4050);
PAINT GREEN (-1750 4050);
DISPLAY INVISIBLE (-1750 4050);
FORCEPROP 1 LAST HDL_TAP TRUE
J 2
(-2075 3975);
DISPLAY 1.234043 (-2075 3975);
PAINT GREEN (-2075 3975);
DISPLAY INVISIBLE (-2075 3975);
FORCEPROP 1 LAST PATH I50
J 2
(-1750 4100);
DISPLAY 0.936170 (-1750 4100);
PAINT GREEN (-1750 4100);
DISPLAY INVISIBLE (-1750 4100);
FORCEADD TAP..6
R 2
(-1750 4150);
FORCEPROP 3 LASTPIN (-1800 4150) SIG_NAME M_M_DQ<49>
J 0
(-1790 4160);
DISPLAY 0.659574 (-1790 4160);
PAINT MONO (-1790 4160);
DISPLAY INVISIBLE (-1790 4160);
FORCEPROP 1 LASTPIN (-1800 4150) BN 49
J 2
(-1750 4160);
DISPLAY 0.617021 (-1750 4160);
PAINT PINK (-1750 4160);
FORCEPROP 2 LAST CDS_LIB mstr_standard
J 2
(-1750 4150);
DISPLAY 0.787234 (-1750 4150);
PAINT MONO (-1750 4150);
DISPLAY INVISIBLE (-1750 4150);
FORCEPROP 1 LAST BODY_TYPE PLUMBING
J 2
(-1750 4100);
DISPLAY 1.234043 (-1750 4100);
PAINT GREEN (-1750 4100);
DISPLAY INVISIBLE (-1750 4100);
FORCEPROP 1 LAST HDL_TAP TRUE
J 2
(-2075 4025);
DISPLAY 1.234043 (-2075 4025);
PAINT GREEN (-2075 4025);
DISPLAY INVISIBLE (-2075 4025);
FORCEPROP 1 LAST PATH I51
J 2
(-1750 4150);
DISPLAY 0.936170 (-1750 4150);
PAINT GREEN (-1750 4150);
DISPLAY INVISIBLE (-1750 4150);
FORCEADD TAP..6
R 2
(-1750 4050);
FORCEPROP 3 LASTPIN (-1800 4050) SIG_NAME M_M_DQ<47>
J 0
(-1790 4060);
DISPLAY 0.659574 (-1790 4060);
PAINT MONO (-1790 4060);
DISPLAY INVISIBLE (-1790 4060);
FORCEPROP 1 LASTPIN (-1800 4050) BN 47
J 2
(-1750 4060);
DISPLAY 0.617021 (-1750 4060);
PAINT PINK (-1750 4060);
FORCEPROP 2 LAST CDS_LIB mstr_standard
J 2
(-1750 4050);
DISPLAY 0.787234 (-1750 4050);
PAINT MONO (-1750 4050);
DISPLAY INVISIBLE (-1750 4050);
FORCEPROP 1 LAST BODY_TYPE PLUMBING
J 2
(-1750 4000);
DISPLAY 1.234043 (-1750 4000);
PAINT GREEN (-1750 4000);
DISPLAY INVISIBLE (-1750 4000);
FORCEPROP 1 LAST HDL_TAP TRUE
J 2
(-2075 3925);
DISPLAY 1.234043 (-2075 3925);
PAINT GREEN (-2075 3925);
DISPLAY INVISIBLE (-2075 3925);
FORCEPROP 1 LAST PATH I52
J 2
(-1750 4050);
DISPLAY 0.936170 (-1750 4050);
PAINT GREEN (-1750 4050);
DISPLAY INVISIBLE (-1750 4050);
FORCEADD TAP..6
R 2
(-1750 3950);
FORCEPROP 3 LASTPIN (-1800 3950) SIG_NAME M_M_DQ<45>
J 0
(-1790 3960);
DISPLAY 0.659574 (-1790 3960);
PAINT MONO (-1790 3960);
DISPLAY INVISIBLE (-1790 3960);
FORCEPROP 1 LASTPIN (-1800 3950) BN 45
J 2
(-1750 3960);
DISPLAY 0.617021 (-1750 3960);
PAINT PINK (-1750 3960);
FORCEPROP 2 LAST CDS_LIB mstr_standard
J 2
(-1750 3950);
DISPLAY 0.787234 (-1750 3950);
PAINT MONO (-1750 3950);
DISPLAY INVISIBLE (-1750 3950);
FORCEPROP 1 LAST BODY_TYPE PLUMBING
J 2
(-1750 3900);
DISPLAY 1.234043 (-1750 3900);
PAINT GREEN (-1750 3900);
DISPLAY INVISIBLE (-1750 3900);
FORCEPROP 1 LAST HDL_TAP TRUE
J 2
(-2075 3825);
DISPLAY 1.234043 (-2075 3825);
PAINT GREEN (-2075 3825);
DISPLAY INVISIBLE (-2075 3825);
FORCEPROP 1 LAST PATH I53
J 2
(-1750 3950);
DISPLAY 0.936170 (-1750 3950);
PAINT GREEN (-1750 3950);
DISPLAY INVISIBLE (-1750 3950);
FORCEADD TAP..6
R 2
(-1750 4000);
FORCEPROP 3 LASTPIN (-1800 4000) SIG_NAME M_M_DQ<44>
J 0
(-1790 4010);
DISPLAY 0.659574 (-1790 4010);
PAINT MONO (-1790 4010);
DISPLAY INVISIBLE (-1790 4010);
FORCEPROP 1 LASTPIN (-1800 4000) BN 44
J 2
(-1750 4010);
DISPLAY 0.617021 (-1750 4010);
PAINT PINK (-1750 4010);
FORCEPROP 2 LAST CDS_LIB mstr_standard
J 2
(-1750 4000);
DISPLAY 0.787234 (-1750 4000);
PAINT MONO (-1750 4000);
DISPLAY INVISIBLE (-1750 4000);
FORCEPROP 1 LAST BODY_TYPE PLUMBING
J 2
(-1750 3950);
DISPLAY 1.234043 (-1750 3950);
PAINT GREEN (-1750 3950);
DISPLAY INVISIBLE (-1750 3950);
FORCEPROP 1 LAST HDL_TAP TRUE
J 2
(-2075 3875);
DISPLAY 1.234043 (-2075 3875);
PAINT GREEN (-2075 3875);
DISPLAY INVISIBLE (-2075 3875);
FORCEPROP 1 LAST PATH I54
J 2
(-1750 4000);
DISPLAY 0.936170 (-1750 4000);
PAINT GREEN (-1750 4000);
DISPLAY INVISIBLE (-1750 4000);
FORCEADD TAP..6
R 2
(700 4250);
FORCEPROP 3 LASTPIN (650 4250) SIG_NAME M_M_DQS_DP<8>
J 0
(660 4260);
DISPLAY 0.659574 (660 4260);
PAINT MONO (660 4260);
DISPLAY INVISIBLE (660 4260);
FORCEPROP 1 LASTPIN (650 4250) BN 8
J 2
(700 4260);
DISPLAY 0.617021 (700 4260);
PAINT PINK (700 4260);
FORCEPROP 2 LAST CDS_LIB mstr_standard
J 0
(700 4250);
DISPLAY 0.787234 (700 4250);
PAINT MONO (700 4250);
DISPLAY INVISIBLE (700 4250);
FORCEPROP 1 LAST BODY_TYPE PLUMBING
J 2
(700 4200);
DISPLAY 1.234043 (700 4200);
PAINT GREEN (700 4200);
DISPLAY INVISIBLE (700 4200);
FORCEPROP 1 LAST HDL_TAP TRUE
J 2
(375 4125);
DISPLAY 1.234043 (375 4125);
PAINT GREEN (375 4125);
DISPLAY INVISIBLE (375 4125);
FORCEPROP 1 LAST PATH I55
J 2
(700 4250);
DISPLAY 0.936170 (700 4250);
PAINT GREEN (700 4250);
DISPLAY INVISIBLE (700 4250);
FORCEADD TAP..6
R 2
(700 4150);
FORCEPROP 3 LASTPIN (650 4150) SIG_NAME M_M_DQS_DP<7>
J 0
(660 4160);
DISPLAY 0.659574 (660 4160);
PAINT MONO (660 4160);
DISPLAY INVISIBLE (660 4160);
FORCEPROP 1 LASTPIN (650 4150) BN 7
J 2
(700 4160);
DISPLAY 0.617021 (700 4160);
PAINT PINK (700 4160);
FORCEPROP 2 LAST CDS_LIB mstr_standard
J 0
(700 4150);
DISPLAY 0.787234 (700 4150);
PAINT MONO (700 4150);
DISPLAY INVISIBLE (700 4150);
FORCEPROP 1 LAST BODY_TYPE PLUMBING
J 2
(700 4100);
DISPLAY 1.234043 (700 4100);
PAINT GREEN (700 4100);
DISPLAY INVISIBLE (700 4100);
FORCEPROP 1 LAST HDL_TAP TRUE
J 2
(375 4025);
DISPLAY 1.234043 (375 4025);
PAINT GREEN (375 4025);
DISPLAY INVISIBLE (375 4025);
FORCEPROP 1 LAST PATH I56
J 2
(700 4150);
DISPLAY 0.936170 (700 4150);
PAINT GREEN (700 4150);
DISPLAY INVISIBLE (700 4150);
FORCEADD TAP..6
R 2
(700 4050);
FORCEPROP 3 LASTPIN (650 4050) SIG_NAME M_M_DQS_DP<6>
J 0
(660 4060);
DISPLAY 0.659574 (660 4060);
PAINT MONO (660 4060);
DISPLAY INVISIBLE (660 4060);
FORCEPROP 1 LASTPIN (650 4050) BN 6
J 2
(700 4060);
DISPLAY 0.617021 (700 4060);
PAINT PINK (700 4060);
FORCEPROP 2 LAST CDS_LIB mstr_standard
J 0
(700 4050);
DISPLAY 0.787234 (700 4050);
PAINT MONO (700 4050);
DISPLAY INVISIBLE (700 4050);
FORCEPROP 1 LAST BODY_TYPE PLUMBING
J 2
(700 4000);
DISPLAY 1.234043 (700 4000);
PAINT GREEN (700 4000);
DISPLAY INVISIBLE (700 4000);
FORCEPROP 1 LAST HDL_TAP TRUE
J 2
(375 3925);
DISPLAY 1.234043 (375 3925);
PAINT GREEN (375 3925);
DISPLAY INVISIBLE (375 3925);
FORCEPROP 1 LAST PATH I57
J 2
(700 4050);
DISPLAY 0.936170 (700 4050);
PAINT GREEN (700 4050);
DISPLAY INVISIBLE (700 4050);
FORCEADD TAP..6
R 2
(700 4350);
FORCEPROP 3 LASTPIN (650 4350) SIG_NAME M_M_DQS_DP<9>
J 0
(660 4360);
DISPLAY 0.659574 (660 4360);
PAINT MONO (660 4360);
DISPLAY INVISIBLE (660 4360);
FORCEPROP 1 LASTPIN (650 4350) BN 9
J 2
(700 4360);
DISPLAY 0.617021 (700 4360);
PAINT PINK (700 4360);
FORCEPROP 2 LAST CDS_LIB mstr_standard
J 0
(700 4350);
DISPLAY 0.787234 (700 4350);
PAINT MONO (700 4350);
DISPLAY INVISIBLE (700 4350);
FORCEPROP 1 LAST BODY_TYPE PLUMBING
J 2
(700 4300);
DISPLAY 1.234043 (700 4300);
PAINT GREEN (700 4300);
DISPLAY INVISIBLE (700 4300);
FORCEPROP 1 LAST HDL_TAP TRUE
J 2
(375 4225);
DISPLAY 1.234043 (375 4225);
PAINT GREEN (375 4225);
DISPLAY INVISIBLE (375 4225);
FORCEPROP 1 LAST PATH I58
J 2
(700 4350);
DISPLAY 0.936170 (700 4350);
PAINT GREEN (700 4350);
DISPLAY INVISIBLE (700 4350);
FORCEADD TAP..6
R 2
(700 4450);
FORCEPROP 3 LASTPIN (650 4450) SIG_NAME M_M_DQS_DP<10>
J 0
(660 4460);
DISPLAY 0.659574 (660 4460);
PAINT MONO (660 4460);
DISPLAY INVISIBLE (660 4460);
FORCEPROP 1 LASTPIN (650 4450) BN 10
J 2
(700 4460);
DISPLAY 0.617021 (700 4460);
PAINT PINK (700 4460);
FORCEPROP 2 LAST CDS_LIB mstr_standard
J 0
(700 4450);
DISPLAY 0.787234 (700 4450);
PAINT MONO (700 4450);
DISPLAY INVISIBLE (700 4450);
FORCEPROP 1 LAST BODY_TYPE PLUMBING
J 2
(700 4400);
DISPLAY 1.234043 (700 4400);
PAINT GREEN (700 4400);
DISPLAY INVISIBLE (700 4400);
FORCEPROP 1 LAST HDL_TAP TRUE
J 2
(375 4325);
DISPLAY 1.234043 (375 4325);
PAINT GREEN (375 4325);
DISPLAY INVISIBLE (375 4325);
FORCEPROP 1 LAST PATH I59
J 2
(700 4450);
DISPLAY 0.936170 (700 4450);
PAINT GREEN (700 4450);
DISPLAY INVISIBLE (700 4450);
FORCEADD TAP..6
R 2
(900 4800);
FORCEPROP 3 LASTPIN (850 4800) SIG_NAME M_M_DQS_DN<14>
J 0
(860 4810);
DISPLAY 0.659574 (860 4810);
PAINT MONO (860 4810);
DISPLAY INVISIBLE (860 4810);
FORCEPROP 1 LASTPIN (850 4800) BN 14
J 2
(900 4810);
DISPLAY 0.617021 (900 4810);
PAINT PINK (900 4810);
FORCEPROP 2 LAST CDS_LIB mstr_standard
J 0
(900 4800);
DISPLAY 0.787234 (900 4800);
PAINT MONO (900 4800);
DISPLAY INVISIBLE (900 4800);
FORCEPROP 1 LAST BODY_TYPE PLUMBING
J 2
(900 4750);
DISPLAY 1.234043 (900 4750);
PAINT GREEN (900 4750);
DISPLAY INVISIBLE (900 4750);
FORCEPROP 1 LAST HDL_TAP TRUE
J 2
(575 4675);
DISPLAY 1.234043 (575 4675);
PAINT GREEN (575 4675);
DISPLAY INVISIBLE (575 4675);
FORCEPROP 1 LAST PATH I6
J 2
(900 4800);
DISPLAY 0.936170 (900 4800);
PAINT GREEN (900 4800);
DISPLAY INVISIBLE (900 4800);
FORCEADD TAP..6
R 2
(700 3750);
FORCEPROP 3 LASTPIN (650 3750) SIG_NAME M_M_DQS_DP<3>
J 0
(660 3760);
DISPLAY 0.659574 (660 3760);
PAINT MONO (660 3760);
DISPLAY INVISIBLE (660 3760);
FORCEPROP 1 LASTPIN (650 3750) BN 3
J 2
(700 3760);
DISPLAY 0.617021 (700 3760);
PAINT PINK (700 3760);
FORCEPROP 2 LAST CDS_LIB mstr_standard
J 0
(700 3750);
DISPLAY 0.787234 (700 3750);
PAINT MONO (700 3750);
DISPLAY INVISIBLE (700 3750);
FORCEPROP 1 LAST BODY_TYPE PLUMBING
J 2
(700 3700);
DISPLAY 1.234043 (700 3700);
PAINT GREEN (700 3700);
DISPLAY INVISIBLE (700 3700);
FORCEPROP 1 LAST HDL_TAP TRUE
J 2
(375 3625);
DISPLAY 1.234043 (375 3625);
PAINT GREEN (375 3625);
DISPLAY INVISIBLE (375 3625);
FORCEPROP 1 LAST PATH I60
J 2
(700 3750);
DISPLAY 0.936170 (700 3750);
PAINT GREEN (700 3750);
DISPLAY INVISIBLE (700 3750);
FORCEADD TAP..6
R 2
(700 3550);
FORCEPROP 3 LASTPIN (650 3550) SIG_NAME M_M_DQS_DP<1>
J 0
(660 3560);
DISPLAY 0.659574 (660 3560);
PAINT MONO (660 3560);
DISPLAY INVISIBLE (660 3560);
FORCEPROP 1 LASTPIN (650 3550) BN 1
J 2
(700 3560);
DISPLAY 0.617021 (700 3560);
PAINT PINK (700 3560);
FORCEPROP 2 LAST CDS_LIB mstr_standard
J 0
(700 3550);
DISPLAY 0.787234 (700 3550);
PAINT MONO (700 3550);
DISPLAY INVISIBLE (700 3550);
FORCEPROP 1 LAST BODY_TYPE PLUMBING
J 2
(700 3500);
DISPLAY 1.234043 (700 3500);
PAINT GREEN (700 3500);
DISPLAY INVISIBLE (700 3500);
FORCEPROP 1 LAST HDL_TAP TRUE
J 2
(375 3425);
DISPLAY 1.234043 (375 3425);
PAINT GREEN (375 3425);
DISPLAY INVISIBLE (375 3425);
FORCEPROP 1 LAST PATH I61
J 2
(700 3550);
DISPLAY 0.936170 (700 3550);
PAINT GREEN (700 3550);
DISPLAY INVISIBLE (700 3550);
FORCEADD TAP..6
R 2
(700 3650);
FORCEPROP 3 LASTPIN (650 3650) SIG_NAME M_M_DQS_DP<2>
J 0
(660 3660);
DISPLAY 0.659574 (660 3660);
PAINT MONO (660 3660);
DISPLAY INVISIBLE (660 3660);
FORCEPROP 1 LASTPIN (650 3650) BN 2
J 2
(700 3660);
DISPLAY 0.617021 (700 3660);
PAINT PINK (700 3660);
FORCEPROP 2 LAST CDS_LIB mstr_standard
J 0
(700 3650);
DISPLAY 0.787234 (700 3650);
PAINT MONO (700 3650);
DISPLAY INVISIBLE (700 3650);
FORCEPROP 1 LAST BODY_TYPE PLUMBING
J 2
(700 3600);
DISPLAY 1.234043 (700 3600);
PAINT GREEN (700 3600);
DISPLAY INVISIBLE (700 3600);
FORCEPROP 1 LAST HDL_TAP TRUE
J 2
(375 3525);
DISPLAY 1.234043 (375 3525);
PAINT GREEN (375 3525);
DISPLAY INVISIBLE (375 3525);
FORCEPROP 1 LAST PATH I62
J 2
(700 3650);
DISPLAY 0.936170 (700 3650);
PAINT GREEN (700 3650);
DISPLAY INVISIBLE (700 3650);
FORCEADD TAP..6
R 2
(700 3950);
FORCEPROP 3 LASTPIN (650 3950) SIG_NAME M_M_DQS_DP<5>
J 0
(660 3960);
DISPLAY 0.659574 (660 3960);
PAINT MONO (660 3960);
DISPLAY INVISIBLE (660 3960);
FORCEPROP 1 LASTPIN (650 3950) BN 5
J 2
(700 3960);
DISPLAY 0.617021 (700 3960);
PAINT PINK (700 3960);
FORCEPROP 2 LAST CDS_LIB mstr_standard
J 0
(700 3950);
DISPLAY 0.787234 (700 3950);
PAINT MONO (700 3950);
DISPLAY INVISIBLE (700 3950);
FORCEPROP 1 LAST BODY_TYPE PLUMBING
J 2
(700 3900);
DISPLAY 1.234043 (700 3900);
PAINT GREEN (700 3900);
DISPLAY INVISIBLE (700 3900);
FORCEPROP 1 LAST HDL_TAP TRUE
J 2
(375 3825);
DISPLAY 1.234043 (375 3825);
PAINT GREEN (375 3825);
DISPLAY INVISIBLE (375 3825);
FORCEPROP 1 LAST PATH I63
J 2
(700 3950);
DISPLAY 0.936170 (700 3950);
PAINT GREEN (700 3950);
DISPLAY INVISIBLE (700 3950);
FORCEADD TAP..6
R 2
(700 3850);
FORCEPROP 3 LASTPIN (650 3850) SIG_NAME M_M_DQS_DP<4>
J 0
(660 3860);
DISPLAY 0.659574 (660 3860);
PAINT MONO (660 3860);
DISPLAY INVISIBLE (660 3860);
FORCEPROP 1 LASTPIN (650 3850) BN 4
J 2
(700 3860);
DISPLAY 0.617021 (700 3860);
PAINT PINK (700 3860);
FORCEPROP 2 LAST CDS_LIB mstr_standard
J 0
(700 3850);
DISPLAY 0.787234 (700 3850);
PAINT MONO (700 3850);
DISPLAY INVISIBLE (700 3850);
FORCEPROP 1 LAST BODY_TYPE PLUMBING
J 2
(700 3800);
DISPLAY 1.234043 (700 3800);
PAINT GREEN (700 3800);
DISPLAY INVISIBLE (700 3800);
FORCEPROP 1 LAST HDL_TAP TRUE
J 2
(375 3725);
DISPLAY 1.234043 (375 3725);
PAINT GREEN (375 3725);
DISPLAY INVISIBLE (375 3725);
FORCEPROP 1 LAST PATH I64
J 2
(700 3850);
DISPLAY 0.936170 (700 3850);
PAINT GREEN (700 3850);
DISPLAY INVISIBLE (700 3850);
FORCEADD TAP..6
R 2
(700 3450);
FORCEPROP 3 LASTPIN (650 3450) SIG_NAME M_M_DQS_DP<0>
J 0
(660 3460);
DISPLAY 0.659574 (660 3460);
PAINT MONO (660 3460);
DISPLAY INVISIBLE (660 3460);
FORCEPROP 1 LASTPIN (650 3450) BN 0
J 2
(700 3460);
DISPLAY 0.617021 (700 3460);
PAINT PINK (700 3460);
FORCEPROP 2 LAST CDS_LIB mstr_standard
J 0
(700 3450);
DISPLAY 0.787234 (700 3450);
PAINT MONO (700 3450);
DISPLAY INVISIBLE (700 3450);
FORCEPROP 1 LAST BODY_TYPE PLUMBING
J 2
(700 3400);
DISPLAY 1.234043 (700 3400);
PAINT GREEN (700 3400);
DISPLAY INVISIBLE (700 3400);
FORCEPROP 1 LAST HDL_TAP TRUE
J 2
(375 3325);
DISPLAY 1.234043 (375 3325);
PAINT GREEN (375 3325);
DISPLAY INVISIBLE (375 3325);
FORCEPROP 1 LAST PATH I65
J 2
(700 3450);
DISPLAY 0.936170 (700 3450);
PAINT GREEN (700 3450);
DISPLAY INVISIBLE (700 3450);
FORCEADD TAP..6
R 2
(-1750 3900);
FORCEPROP 3 LASTPIN (-1800 3900) SIG_NAME M_M_DQ<42>
J 0
(-1790 3910);
DISPLAY 0.659574 (-1790 3910);
PAINT MONO (-1790 3910);
DISPLAY INVISIBLE (-1790 3910);
FORCEPROP 1 LASTPIN (-1800 3900) BN 42
J 2
(-1750 3910);
DISPLAY 0.617021 (-1750 3910);
PAINT PINK (-1750 3910);
FORCEPROP 2 LAST CDS_LIB mstr_standard
J 2
(-1750 3900);
DISPLAY 0.787234 (-1750 3900);
PAINT MONO (-1750 3900);
DISPLAY INVISIBLE (-1750 3900);
FORCEPROP 1 LAST BODY_TYPE PLUMBING
J 2
(-1750 3850);
DISPLAY 1.234043 (-1750 3850);
PAINT GREEN (-1750 3850);
DISPLAY INVISIBLE (-1750 3850);
FORCEPROP 1 LAST HDL_TAP TRUE
J 2
(-2075 3775);
DISPLAY 1.234043 (-2075 3775);
PAINT GREEN (-2075 3775);
DISPLAY INVISIBLE (-2075 3775);
FORCEPROP 1 LAST PATH I66
J 2
(-1750 3900);
DISPLAY 0.936170 (-1750 3900);
PAINT GREEN (-1750 3900);
DISPLAY INVISIBLE (-1750 3900);
FORCEADD TAP..6
R 2
(-1750 3850);
FORCEPROP 3 LASTPIN (-1800 3850) SIG_NAME M_M_DQ<43>
J 0
(-1790 3860);
DISPLAY 0.659574 (-1790 3860);
PAINT MONO (-1790 3860);
DISPLAY INVISIBLE (-1790 3860);
FORCEPROP 1 LASTPIN (-1800 3850) BN 43
J 2
(-1750 3860);
DISPLAY 0.617021 (-1750 3860);
PAINT PINK (-1750 3860);
FORCEPROP 2 LAST CDS_LIB mstr_standard
J 2
(-1750 3850);
DISPLAY 0.787234 (-1750 3850);
PAINT MONO (-1750 3850);
DISPLAY INVISIBLE (-1750 3850);
FORCEPROP 1 LAST BODY_TYPE PLUMBING
J 2
(-1750 3800);
DISPLAY 1.234043 (-1750 3800);
PAINT GREEN (-1750 3800);
DISPLAY INVISIBLE (-1750 3800);
FORCEPROP 1 LAST HDL_TAP TRUE
J 2
(-2075 3725);
DISPLAY 1.234043 (-2075 3725);
PAINT GREEN (-2075 3725);
DISPLAY INVISIBLE (-2075 3725);
FORCEPROP 1 LAST PATH I67
J 2
(-1750 3850);
DISPLAY 0.936170 (-1750 3850);
PAINT GREEN (-1750 3850);
DISPLAY INVISIBLE (-1750 3850);
FORCEADD TAP..6
R 2
(-1750 3750);
FORCEPROP 3 LASTPIN (-1800 3750) SIG_NAME M_M_DQ<41>
J 0
(-1790 3760);
DISPLAY 0.659574 (-1790 3760);
PAINT MONO (-1790 3760);
DISPLAY INVISIBLE (-1790 3760);
FORCEPROP 1 LASTPIN (-1800 3750) BN 41
J 2
(-1750 3760);
DISPLAY 0.617021 (-1750 3760);
PAINT PINK (-1750 3760);
FORCEPROP 2 LAST CDS_LIB mstr_standard
J 2
(-1750 3750);
DISPLAY 0.787234 (-1750 3750);
PAINT MONO (-1750 3750);
DISPLAY INVISIBLE (-1750 3750);
FORCEPROP 1 LAST BODY_TYPE PLUMBING
J 2
(-1750 3700);
DISPLAY 1.234043 (-1750 3700);
PAINT GREEN (-1750 3700);
DISPLAY INVISIBLE (-1750 3700);
FORCEPROP 1 LAST HDL_TAP TRUE
J 2
(-2075 3625);
DISPLAY 1.234043 (-2075 3625);
PAINT GREEN (-2075 3625);
DISPLAY INVISIBLE (-2075 3625);
FORCEPROP 1 LAST PATH I68
J 2
(-1750 3750);
DISPLAY 0.936170 (-1750 3750);
PAINT GREEN (-1750 3750);
DISPLAY INVISIBLE (-1750 3750);
FORCEADD TAP..6
R 2
(-1750 3800);
FORCEPROP 3 LASTPIN (-1800 3800) SIG_NAME M_M_DQ<40>
J 0
(-1790 3810);
DISPLAY 0.659574 (-1790 3810);
PAINT MONO (-1790 3810);
DISPLAY INVISIBLE (-1790 3810);
FORCEPROP 1 LASTPIN (-1800 3800) BN 40
J 2
(-1750 3810);
DISPLAY 0.617021 (-1750 3810);
PAINT PINK (-1750 3810);
FORCEPROP 2 LAST CDS_LIB mstr_standard
J 2
(-1750 3800);
DISPLAY 0.787234 (-1750 3800);
PAINT MONO (-1750 3800);
DISPLAY INVISIBLE (-1750 3800);
FORCEPROP 1 LAST BODY_TYPE PLUMBING
J 2
(-1750 3750);
DISPLAY 1.234043 (-1750 3750);
PAINT GREEN (-1750 3750);
DISPLAY INVISIBLE (-1750 3750);
FORCEPROP 1 LAST HDL_TAP TRUE
J 2
(-2075 3675);
DISPLAY 1.234043 (-2075 3675);
PAINT GREEN (-2075 3675);
DISPLAY INVISIBLE (-2075 3675);
FORCEPROP 1 LAST PATH I69
J 2
(-1750 3800);
DISPLAY 0.936170 (-1750 3800);
PAINT GREEN (-1750 3800);
DISPLAY INVISIBLE (-1750 3800);
FORCEADD TAP..6
R 2
(900 4700);
FORCEPROP 3 LASTPIN (850 4700) SIG_NAME M_M_DQS_DN<13>
J 0
(860 4710);
DISPLAY 0.659574 (860 4710);
PAINT MONO (860 4710);
DISPLAY INVISIBLE (860 4710);
FORCEPROP 1 LASTPIN (850 4700) BN 13
J 2
(900 4710);
DISPLAY 0.617021 (900 4710);
PAINT PINK (900 4710);
FORCEPROP 2 LAST CDS_LIB mstr_standard
J 0
(900 4700);
DISPLAY 0.787234 (900 4700);
PAINT MONO (900 4700);
DISPLAY INVISIBLE (900 4700);
FORCEPROP 1 LAST BODY_TYPE PLUMBING
J 2
(900 4650);
DISPLAY 1.234043 (900 4650);
PAINT GREEN (900 4650);
DISPLAY INVISIBLE (900 4650);
FORCEPROP 1 LAST HDL_TAP TRUE
J 2
(575 4575);
DISPLAY 1.234043 (575 4575);
PAINT GREEN (575 4575);
DISPLAY INVISIBLE (575 4575);
FORCEPROP 1 LAST PATH I7
J 2
(900 4700);
DISPLAY 0.936170 (900 4700);
PAINT GREEN (900 4700);
DISPLAY INVISIBLE (900 4700);
FORCEADD TAP..6
R 2
(-1750 3700);
FORCEPROP 3 LASTPIN (-1800 3700) SIG_NAME M_M_DQ<38>
J 0
(-1790 3710);
DISPLAY 0.659574 (-1790 3710);
PAINT MONO (-1790 3710);
DISPLAY INVISIBLE (-1790 3710);
FORCEPROP 1 LASTPIN (-1800 3700) BN 38
J 2
(-1750 3710);
DISPLAY 0.617021 (-1750 3710);
PAINT PINK (-1750 3710);
FORCEPROP 2 LAST CDS_LIB mstr_standard
J 2
(-1750 3700);
DISPLAY 0.787234 (-1750 3700);
PAINT MONO (-1750 3700);
DISPLAY INVISIBLE (-1750 3700);
FORCEPROP 1 LAST BODY_TYPE PLUMBING
J 2
(-1750 3650);
DISPLAY 1.234043 (-1750 3650);
PAINT GREEN (-1750 3650);
DISPLAY INVISIBLE (-1750 3650);
FORCEPROP 1 LAST HDL_TAP TRUE
J 2
(-2075 3575);
DISPLAY 1.234043 (-2075 3575);
PAINT GREEN (-2075 3575);
DISPLAY INVISIBLE (-2075 3575);
FORCEPROP 1 LAST PATH I70
J 2
(-1750 3700);
DISPLAY 0.936170 (-1750 3700);
PAINT GREEN (-1750 3700);
DISPLAY INVISIBLE (-1750 3700);
FORCEADD TAP..6
R 2
(-1750 3650);
FORCEPROP 3 LASTPIN (-1800 3650) SIG_NAME M_M_DQ<39>
J 0
(-1790 3660);
DISPLAY 0.659574 (-1790 3660);
PAINT MONO (-1790 3660);
DISPLAY INVISIBLE (-1790 3660);
FORCEPROP 1 LASTPIN (-1800 3650) BN 39
J 2
(-1750 3660);
DISPLAY 0.617021 (-1750 3660);
PAINT PINK (-1750 3660);
FORCEPROP 2 LAST CDS_LIB mstr_standard
J 2
(-1750 3650);
DISPLAY 0.787234 (-1750 3650);
PAINT MONO (-1750 3650);
DISPLAY INVISIBLE (-1750 3650);
FORCEPROP 1 LAST BODY_TYPE PLUMBING
J 2
(-1750 3600);
DISPLAY 1.234043 (-1750 3600);
PAINT GREEN (-1750 3600);
DISPLAY INVISIBLE (-1750 3600);
FORCEPROP 1 LAST HDL_TAP TRUE
J 2
(-2075 3525);
DISPLAY 1.234043 (-2075 3525);
PAINT GREEN (-2075 3525);
DISPLAY INVISIBLE (-2075 3525);
FORCEPROP 1 LAST PATH I71
J 2
(-1750 3650);
DISPLAY 0.936170 (-1750 3650);
PAINT GREEN (-1750 3650);
DISPLAY INVISIBLE (-1750 3650);
FORCEADD TAP..6
R 2
(-1750 3600);
FORCEPROP 3 LASTPIN (-1800 3600) SIG_NAME M_M_DQ<36>
J 0
(-1790 3610);
DISPLAY 0.659574 (-1790 3610);
PAINT MONO (-1790 3610);
DISPLAY INVISIBLE (-1790 3610);
FORCEPROP 1 LASTPIN (-1800 3600) BN 36
J 2
(-1750 3610);
DISPLAY 0.617021 (-1750 3610);
PAINT PINK (-1750 3610);
FORCEPROP 2 LAST CDS_LIB mstr_standard
J 2
(-1750 3600);
DISPLAY 0.787234 (-1750 3600);
PAINT MONO (-1750 3600);
DISPLAY INVISIBLE (-1750 3600);
FORCEPROP 1 LAST BODY_TYPE PLUMBING
J 2
(-1750 3550);
DISPLAY 1.234043 (-1750 3550);
PAINT GREEN (-1750 3550);
DISPLAY INVISIBLE (-1750 3550);
FORCEPROP 1 LAST HDL_TAP TRUE
J 2
(-2075 3475);
DISPLAY 1.234043 (-2075 3475);
PAINT GREEN (-2075 3475);
DISPLAY INVISIBLE (-2075 3475);
FORCEPROP 1 LAST PATH I72
J 2
(-1750 3600);
DISPLAY 0.936170 (-1750 3600);
PAINT GREEN (-1750 3600);
DISPLAY INVISIBLE (-1750 3600);
FORCEADD TAP..6
R 2
(-1750 3550);
FORCEPROP 3 LASTPIN (-1800 3550) SIG_NAME M_M_DQ<37>
J 0
(-1790 3560);
DISPLAY 0.659574 (-1790 3560);
PAINT MONO (-1790 3560);
DISPLAY INVISIBLE (-1790 3560);
FORCEPROP 1 LASTPIN (-1800 3550) BN 37
J 2
(-1750 3560);
DISPLAY 0.617021 (-1750 3560);
PAINT PINK (-1750 3560);
FORCEPROP 2 LAST CDS_LIB mstr_standard
J 2
(-1750 3550);
DISPLAY 0.787234 (-1750 3550);
PAINT MONO (-1750 3550);
DISPLAY INVISIBLE (-1750 3550);
FORCEPROP 1 LAST BODY_TYPE PLUMBING
J 2
(-1750 3500);
DISPLAY 1.234043 (-1750 3500);
PAINT GREEN (-1750 3500);
DISPLAY INVISIBLE (-1750 3500);
FORCEPROP 1 LAST HDL_TAP TRUE
J 2
(-2075 3425);
DISPLAY 1.234043 (-2075 3425);
PAINT GREEN (-2075 3425);
DISPLAY INVISIBLE (-2075 3425);
FORCEPROP 1 LAST PATH I73
J 2
(-1750 3550);
DISPLAY 0.936170 (-1750 3550);
PAINT GREEN (-1750 3550);
DISPLAY INVISIBLE (-1750 3550);
FORCEADD TAP..6
R 2
(-1750 3500);
FORCEPROP 3 LASTPIN (-1800 3500) SIG_NAME M_M_DQ<34>
J 0
(-1790 3510);
DISPLAY 0.659574 (-1790 3510);
PAINT MONO (-1790 3510);
DISPLAY INVISIBLE (-1790 3510);
FORCEPROP 1 LASTPIN (-1800 3500) BN 34
J 2
(-1750 3510);
DISPLAY 0.617021 (-1750 3510);
PAINT PINK (-1750 3510);
FORCEPROP 2 LAST CDS_LIB mstr_standard
J 2
(-1750 3500);
DISPLAY 0.787234 (-1750 3500);
PAINT MONO (-1750 3500);
DISPLAY INVISIBLE (-1750 3500);
FORCEPROP 1 LAST BODY_TYPE PLUMBING
J 2
(-1750 3450);
DISPLAY 1.234043 (-1750 3450);
PAINT GREEN (-1750 3450);
DISPLAY INVISIBLE (-1750 3450);
FORCEPROP 1 LAST HDL_TAP TRUE
J 2
(-2075 3375);
DISPLAY 1.234043 (-2075 3375);
PAINT GREEN (-2075 3375);
DISPLAY INVISIBLE (-2075 3375);
FORCEPROP 1 LAST PATH I74
J 2
(-1750 3500);
DISPLAY 0.936170 (-1750 3500);
PAINT GREEN (-1750 3500);
DISPLAY INVISIBLE (-1750 3500);
FORCEADD TAP..6
R 2
(-1750 3450);
FORCEPROP 3 LASTPIN (-1800 3450) SIG_NAME M_M_DQ<35>
J 0
(-1790 3460);
DISPLAY 0.659574 (-1790 3460);
PAINT MONO (-1790 3460);
DISPLAY INVISIBLE (-1790 3460);
FORCEPROP 1 LASTPIN (-1800 3450) BN 35
J 2
(-1750 3460);
DISPLAY 0.617021 (-1750 3460);
PAINT PINK (-1750 3460);
FORCEPROP 2 LAST CDS_LIB mstr_standard
J 2
(-1750 3450);
DISPLAY 0.787234 (-1750 3450);
PAINT MONO (-1750 3450);
DISPLAY INVISIBLE (-1750 3450);
FORCEPROP 1 LAST BODY_TYPE PLUMBING
J 2
(-1750 3400);
DISPLAY 1.234043 (-1750 3400);
PAINT GREEN (-1750 3400);
DISPLAY INVISIBLE (-1750 3400);
FORCEPROP 1 LAST HDL_TAP TRUE
J 2
(-2075 3325);
DISPLAY 1.234043 (-2075 3325);
PAINT GREEN (-2075 3325);
DISPLAY INVISIBLE (-2075 3325);
FORCEPROP 1 LAST PATH I75
J 2
(-1750 3450);
DISPLAY 0.936170 (-1750 3450);
PAINT GREEN (-1750 3450);
DISPLAY INVISIBLE (-1750 3450);
FORCEADD TAP..6
R 2
(-1750 3400);
FORCEPROP 3 LASTPIN (-1800 3400) SIG_NAME M_M_DQ<32>
J 0
(-1790 3410);
DISPLAY 0.659574 (-1790 3410);
PAINT MONO (-1790 3410);
DISPLAY INVISIBLE (-1790 3410);
FORCEPROP 1 LASTPIN (-1800 3400) BN 32
J 2
(-1750 3410);
DISPLAY 0.617021 (-1750 3410);
PAINT PINK (-1750 3410);
FORCEPROP 2 LAST CDS_LIB mstr_standard
J 2
(-1750 3400);
DISPLAY 0.787234 (-1750 3400);
PAINT MONO (-1750 3400);
DISPLAY INVISIBLE (-1750 3400);
FORCEPROP 1 LAST BODY_TYPE PLUMBING
J 2
(-1750 3350);
DISPLAY 1.234043 (-1750 3350);
PAINT GREEN (-1750 3350);
DISPLAY INVISIBLE (-1750 3350);
FORCEPROP 1 LAST HDL_TAP TRUE
J 2
(-2075 3275);
DISPLAY 1.234043 (-2075 3275);
PAINT GREEN (-2075 3275);
DISPLAY INVISIBLE (-2075 3275);
FORCEPROP 1 LAST PATH I76
J 2
(-1750 3400);
DISPLAY 0.936170 (-1750 3400);
PAINT GREEN (-1750 3400);
DISPLAY INVISIBLE (-1750 3400);
FORCEADD TAP..6
R 2
(-1750 3350);
FORCEPROP 3 LASTPIN (-1800 3350) SIG_NAME M_M_DQ<33>
J 0
(-1790 3360);
DISPLAY 0.659574 (-1790 3360);
PAINT MONO (-1790 3360);
DISPLAY INVISIBLE (-1790 3360);
FORCEPROP 1 LASTPIN (-1800 3350) BN 33
J 2
(-1750 3360);
DISPLAY 0.617021 (-1750 3360);
PAINT PINK (-1750 3360);
FORCEPROP 2 LAST CDS_LIB mstr_standard
J 2
(-1750 3350);
DISPLAY 0.787234 (-1750 3350);
PAINT MONO (-1750 3350);
DISPLAY INVISIBLE (-1750 3350);
FORCEPROP 1 LAST BODY_TYPE PLUMBING
J 2
(-1750 3300);
DISPLAY 1.234043 (-1750 3300);
PAINT GREEN (-1750 3300);
DISPLAY INVISIBLE (-1750 3300);
FORCEPROP 1 LAST HDL_TAP TRUE
J 2
(-2075 3225);
DISPLAY 1.234043 (-2075 3225);
PAINT GREEN (-2075 3225);
DISPLAY INVISIBLE (-2075 3225);
FORCEPROP 1 LAST PATH I77
J 2
(-1750 3350);
DISPLAY 0.936170 (-1750 3350);
PAINT GREEN (-1750 3350);
DISPLAY INVISIBLE (-1750 3350);
FORCEADD TAP..6
R 2
(-1750 3200);
FORCEPROP 3 LASTPIN (-1800 3200) SIG_NAME M_M_DQ<28>
J 0
(-1790 3210);
DISPLAY 0.659574 (-1790 3210);
PAINT MONO (-1790 3210);
DISPLAY INVISIBLE (-1790 3210);
FORCEPROP 1 LASTPIN (-1800 3200) BN 28
J 2
(-1750 3210);
DISPLAY 0.617021 (-1750 3210);
PAINT PINK (-1750 3210);
FORCEPROP 2 LAST CDS_LIB mstr_standard
J 2
(-1750 3200);
DISPLAY 0.787234 (-1750 3200);
PAINT MONO (-1750 3200);
DISPLAY INVISIBLE (-1750 3200);
FORCEPROP 1 LAST BODY_TYPE PLUMBING
J 2
(-1750 3150);
DISPLAY 1.234043 (-1750 3150);
PAINT GREEN (-1750 3150);
DISPLAY INVISIBLE (-1750 3150);
FORCEPROP 1 LAST HDL_TAP TRUE
J 2
(-2075 3075);
DISPLAY 1.234043 (-2075 3075);
PAINT GREEN (-2075 3075);
DISPLAY INVISIBLE (-2075 3075);
FORCEPROP 1 LAST PATH I78
J 2
(-1750 3200);
DISPLAY 0.936170 (-1750 3200);
PAINT GREEN (-1750 3200);
DISPLAY INVISIBLE (-1750 3200);
FORCEADD TAP..6
R 2
(-1750 3250);
FORCEPROP 3 LASTPIN (-1800 3250) SIG_NAME M_M_DQ<31>
J 0
(-1790 3260);
DISPLAY 0.659574 (-1790 3260);
PAINT MONO (-1790 3260);
DISPLAY INVISIBLE (-1790 3260);
FORCEPROP 1 LASTPIN (-1800 3250) BN 31
J 2
(-1750 3260);
DISPLAY 0.617021 (-1750 3260);
PAINT PINK (-1750 3260);
FORCEPROP 2 LAST CDS_LIB mstr_standard
J 2
(-1750 3250);
DISPLAY 0.787234 (-1750 3250);
PAINT MONO (-1750 3250);
DISPLAY INVISIBLE (-1750 3250);
FORCEPROP 1 LAST BODY_TYPE PLUMBING
J 2
(-1750 3200);
DISPLAY 1.234043 (-1750 3200);
PAINT GREEN (-1750 3200);
DISPLAY INVISIBLE (-1750 3200);
FORCEPROP 1 LAST HDL_TAP TRUE
J 2
(-2075 3125);
DISPLAY 1.234043 (-2075 3125);
PAINT GREEN (-2075 3125);
DISPLAY INVISIBLE (-2075 3125);
FORCEPROP 1 LAST PATH I79
J 2
(-1750 3250);
DISPLAY 0.936170 (-1750 3250);
PAINT GREEN (-1750 3250);
DISPLAY INVISIBLE (-1750 3250);
FORCEADD TAP..6
R 2
(900 4600);
FORCEPROP 3 LASTPIN (850 4600) SIG_NAME M_M_DQS_DN<12>
J 0
(860 4610);
DISPLAY 0.659574 (860 4610);
PAINT MONO (860 4610);
DISPLAY INVISIBLE (860 4610);
FORCEPROP 1 LASTPIN (850 4600) BN 12
J 2
(900 4610);
DISPLAY 0.617021 (900 4610);
PAINT PINK (900 4610);
FORCEPROP 2 LAST CDS_LIB mstr_standard
J 0
(900 4600);
DISPLAY 0.787234 (900 4600);
PAINT MONO (900 4600);
DISPLAY INVISIBLE (900 4600);
FORCEPROP 1 LAST BODY_TYPE PLUMBING
J 2
(900 4550);
DISPLAY 1.234043 (900 4550);
PAINT GREEN (900 4550);
DISPLAY INVISIBLE (900 4550);
FORCEPROP 1 LAST HDL_TAP TRUE
J 2
(575 4475);
DISPLAY 1.234043 (575 4475);
PAINT GREEN (575 4475);
DISPLAY INVISIBLE (575 4475);
FORCEPROP 1 LAST PATH I8
J 2
(900 4600);
DISPLAY 0.936170 (900 4600);
PAINT GREEN (900 4600);
DISPLAY INVISIBLE (900 4600);
FORCEADD TAP..6
R 2
(-1750 3300);
FORCEPROP 3 LASTPIN (-1800 3300) SIG_NAME M_M_DQ<30>
J 0
(-1790 3310);
DISPLAY 0.659574 (-1790 3310);
PAINT MONO (-1790 3310);
DISPLAY INVISIBLE (-1790 3310);
FORCEPROP 1 LASTPIN (-1800 3300) BN 30
J 2
(-1750 3310);
DISPLAY 0.617021 (-1750 3310);
PAINT PINK (-1750 3310);
FORCEPROP 2 LAST CDS_LIB mstr_standard
J 2
(-1750 3300);
DISPLAY 0.787234 (-1750 3300);
PAINT MONO (-1750 3300);
DISPLAY INVISIBLE (-1750 3300);
FORCEPROP 1 LAST BODY_TYPE PLUMBING
J 2
(-1750 3250);
DISPLAY 1.234043 (-1750 3250);
PAINT GREEN (-1750 3250);
DISPLAY INVISIBLE (-1750 3250);
FORCEPROP 1 LAST HDL_TAP TRUE
J 2
(-2075 3175);
DISPLAY 1.234043 (-2075 3175);
PAINT GREEN (-2075 3175);
DISPLAY INVISIBLE (-2075 3175);
FORCEPROP 1 LAST PATH I80
J 2
(-1750 3300);
DISPLAY 0.936170 (-1750 3300);
PAINT GREEN (-1750 3300);
DISPLAY INVISIBLE (-1750 3300);
FORCEADD TAP..6
R 2
(-1750 2900);
FORCEPROP 3 LASTPIN (-1800 2900) SIG_NAME M_M_DQ<22>
J 0
(-1790 2910);
DISPLAY 0.659574 (-1790 2910);
PAINT MONO (-1790 2910);
DISPLAY INVISIBLE (-1790 2910);
FORCEPROP 1 LASTPIN (-1800 2900) BN 22
J 2
(-1750 2910);
DISPLAY 0.617021 (-1750 2910);
PAINT PINK (-1750 2910);
FORCEPROP 2 LAST CDS_LIB mstr_standard
J 2
(-1750 2900);
DISPLAY 0.787234 (-1750 2900);
PAINT MONO (-1750 2900);
DISPLAY INVISIBLE (-1750 2900);
FORCEPROP 1 LAST BODY_TYPE PLUMBING
J 2
(-1750 2850);
DISPLAY 1.234043 (-1750 2850);
PAINT GREEN (-1750 2850);
DISPLAY INVISIBLE (-1750 2850);
FORCEPROP 1 LAST HDL_TAP TRUE
J 2
(-2075 2775);
DISPLAY 1.234043 (-2075 2775);
PAINT GREEN (-2075 2775);
DISPLAY INVISIBLE (-2075 2775);
FORCEPROP 1 LAST PATH I81
J 2
(-1750 2900);
DISPLAY 0.936170 (-1750 2900);
PAINT GREEN (-1750 2900);
DISPLAY INVISIBLE (-1750 2900);
FORCEADD TAP..6
R 2
(-1750 3100);
FORCEPROP 3 LASTPIN (-1800 3100) SIG_NAME M_M_DQ<26>
J 0
(-1790 3110);
DISPLAY 0.659574 (-1790 3110);
PAINT MONO (-1790 3110);
DISPLAY INVISIBLE (-1790 3110);
FORCEPROP 1 LASTPIN (-1800 3100) BN 26
J 2
(-1750 3110);
DISPLAY 0.617021 (-1750 3110);
PAINT PINK (-1750 3110);
FORCEPROP 2 LAST CDS_LIB mstr_standard
J 2
(-1750 3100);
DISPLAY 0.787234 (-1750 3100);
PAINT MONO (-1750 3100);
DISPLAY INVISIBLE (-1750 3100);
FORCEPROP 1 LAST BODY_TYPE PLUMBING
J 2
(-1750 3050);
DISPLAY 1.234043 (-1750 3050);
PAINT GREEN (-1750 3050);
DISPLAY INVISIBLE (-1750 3050);
FORCEPROP 1 LAST HDL_TAP TRUE
J 2
(-2075 2975);
DISPLAY 1.234043 (-2075 2975);
PAINT GREEN (-2075 2975);
DISPLAY INVISIBLE (-2075 2975);
FORCEPROP 1 LAST PATH I82
J 2
(-1750 3100);
DISPLAY 0.936170 (-1750 3100);
PAINT GREEN (-1750 3100);
DISPLAY INVISIBLE (-1750 3100);
FORCEADD TAP..6
R 2
(-1750 3150);
FORCEPROP 3 LASTPIN (-1800 3150) SIG_NAME M_M_DQ<29>
J 0
(-1790 3160);
DISPLAY 0.659574 (-1790 3160);
PAINT MONO (-1790 3160);
DISPLAY INVISIBLE (-1790 3160);
FORCEPROP 1 LASTPIN (-1800 3150) BN 29
J 2
(-1750 3160);
DISPLAY 0.617021 (-1750 3160);
PAINT PINK (-1750 3160);
FORCEPROP 2 LAST CDS_LIB mstr_standard
J 2
(-1750 3150);
DISPLAY 0.787234 (-1750 3150);
PAINT MONO (-1750 3150);
DISPLAY INVISIBLE (-1750 3150);
FORCEPROP 1 LAST BODY_TYPE PLUMBING
J 2
(-1750 3100);
DISPLAY 1.234043 (-1750 3100);
PAINT GREEN (-1750 3100);
DISPLAY INVISIBLE (-1750 3100);
FORCEPROP 1 LAST HDL_TAP TRUE
J 2
(-2075 3025);
DISPLAY 1.234043 (-2075 3025);
PAINT GREEN (-2075 3025);
DISPLAY INVISIBLE (-2075 3025);
FORCEPROP 1 LAST PATH I83
J 2
(-1750 3150);
DISPLAY 0.936170 (-1750 3150);
PAINT GREEN (-1750 3150);
DISPLAY INVISIBLE (-1750 3150);
FORCEADD TAP..6
R 2
(-1750 3050);
FORCEPROP 3 LASTPIN (-1800 3050) SIG_NAME M_M_DQ<27>
J 0
(-1790 3060);
DISPLAY 0.659574 (-1790 3060);
PAINT MONO (-1790 3060);
DISPLAY INVISIBLE (-1790 3060);
FORCEPROP 1 LASTPIN (-1800 3050) BN 27
J 2
(-1750 3060);
DISPLAY 0.617021 (-1750 3060);
PAINT PINK (-1750 3060);
FORCEPROP 2 LAST CDS_LIB mstr_standard
J 2
(-1750 3050);
DISPLAY 0.787234 (-1750 3050);
PAINT MONO (-1750 3050);
DISPLAY INVISIBLE (-1750 3050);
FORCEPROP 1 LAST BODY_TYPE PLUMBING
J 2
(-1750 3000);
DISPLAY 1.234043 (-1750 3000);
PAINT GREEN (-1750 3000);
DISPLAY INVISIBLE (-1750 3000);
FORCEPROP 1 LAST HDL_TAP TRUE
J 2
(-2075 2925);
DISPLAY 1.234043 (-2075 2925);
PAINT GREEN (-2075 2925);
DISPLAY INVISIBLE (-2075 2925);
FORCEPROP 1 LAST PATH I84
J 2
(-1750 3050);
DISPLAY 0.936170 (-1750 3050);
PAINT GREEN (-1750 3050);
DISPLAY INVISIBLE (-1750 3050);
FORCEADD TAP..6
R 2
(-1750 3000);
FORCEPROP 3 LASTPIN (-1800 3000) SIG_NAME M_M_DQ<24>
J 0
(-1790 3010);
DISPLAY 0.659574 (-1790 3010);
PAINT MONO (-1790 3010);
DISPLAY INVISIBLE (-1790 3010);
FORCEPROP 1 LASTPIN (-1800 3000) BN 24
J 2
(-1750 3010);
DISPLAY 0.617021 (-1750 3010);
PAINT PINK (-1750 3010);
FORCEPROP 2 LAST CDS_LIB mstr_standard
J 2
(-1750 3000);
DISPLAY 0.787234 (-1750 3000);
PAINT MONO (-1750 3000);
DISPLAY INVISIBLE (-1750 3000);
FORCEPROP 1 LAST BODY_TYPE PLUMBING
J 2
(-1750 2950);
DISPLAY 1.234043 (-1750 2950);
PAINT GREEN (-1750 2950);
DISPLAY INVISIBLE (-1750 2950);
FORCEPROP 1 LAST HDL_TAP TRUE
J 2
(-2075 2875);
DISPLAY 1.234043 (-2075 2875);
PAINT GREEN (-2075 2875);
DISPLAY INVISIBLE (-2075 2875);
FORCEPROP 1 LAST PATH I85
J 2
(-1750 3000);
DISPLAY 0.936170 (-1750 3000);
PAINT GREEN (-1750 3000);
DISPLAY INVISIBLE (-1750 3000);
FORCEADD TAP..6
R 2
(-1750 2950);
FORCEPROP 3 LASTPIN (-1800 2950) SIG_NAME M_M_DQ<25>
J 0
(-1790 2960);
DISPLAY 0.659574 (-1790 2960);
PAINT MONO (-1790 2960);
DISPLAY INVISIBLE (-1790 2960);
FORCEPROP 1 LASTPIN (-1800 2950) BN 25
J 2
(-1750 2960);
DISPLAY 0.617021 (-1750 2960);
PAINT PINK (-1750 2960);
FORCEPROP 2 LAST CDS_LIB mstr_standard
J 2
(-1750 2950);
DISPLAY 0.787234 (-1750 2950);
PAINT MONO (-1750 2950);
DISPLAY INVISIBLE (-1750 2950);
FORCEPROP 1 LAST BODY_TYPE PLUMBING
J 2
(-1750 2900);
DISPLAY 1.234043 (-1750 2900);
PAINT GREEN (-1750 2900);
DISPLAY INVISIBLE (-1750 2900);
FORCEPROP 1 LAST HDL_TAP TRUE
J 2
(-2075 2825);
DISPLAY 1.234043 (-2075 2825);
PAINT GREEN (-2075 2825);
DISPLAY INVISIBLE (-2075 2825);
FORCEPROP 1 LAST PATH I86
J 2
(-1750 2950);
DISPLAY 0.936170 (-1750 2950);
PAINT GREEN (-1750 2950);
DISPLAY INVISIBLE (-1750 2950);
FORCEADD TAP..6
R 2
(-1750 2650);
FORCEPROP 3 LASTPIN (-1800 2650) SIG_NAME M_M_DQ<19>
J 0
(-1790 2660);
DISPLAY 0.659574 (-1790 2660);
PAINT MONO (-1790 2660);
DISPLAY INVISIBLE (-1790 2660);
FORCEPROP 1 LASTPIN (-1800 2650) BN 19
J 2
(-1750 2660);
DISPLAY 0.617021 (-1750 2660);
PAINT PINK (-1750 2660);
FORCEPROP 2 LAST CDS_LIB mstr_standard
J 2
(-1750 2650);
DISPLAY 0.787234 (-1750 2650);
PAINT MONO (-1750 2650);
DISPLAY INVISIBLE (-1750 2650);
FORCEPROP 1 LAST BODY_TYPE PLUMBING
J 2
(-1750 2600);
DISPLAY 1.234043 (-1750 2600);
PAINT GREEN (-1750 2600);
DISPLAY INVISIBLE (-1750 2600);
FORCEPROP 1 LAST HDL_TAP TRUE
J 2
(-2075 2525);
DISPLAY 1.234043 (-2075 2525);
PAINT GREEN (-2075 2525);
DISPLAY INVISIBLE (-2075 2525);
FORCEPROP 1 LAST PATH I88
J 2
(-1750 2650);
DISPLAY 0.936170 (-1750 2650);
PAINT GREEN (-1750 2650);
DISPLAY INVISIBLE (-1750 2650);
FORCEADD TAP..6
R 2
(-1750 2850);
FORCEPROP 3 LASTPIN (-1800 2850) SIG_NAME M_M_DQ<23>
J 0
(-1790 2860);
DISPLAY 0.659574 (-1790 2860);
PAINT MONO (-1790 2860);
DISPLAY INVISIBLE (-1790 2860);
FORCEPROP 1 LASTPIN (-1800 2850) BN 23
J 2
(-1750 2860);
DISPLAY 0.617021 (-1750 2860);
PAINT PINK (-1750 2860);
FORCEPROP 2 LAST CDS_LIB mstr_standard
J 2
(-1750 2850);
DISPLAY 0.787234 (-1750 2850);
PAINT MONO (-1750 2850);
DISPLAY INVISIBLE (-1750 2850);
FORCEPROP 1 LAST BODY_TYPE PLUMBING
J 2
(-1750 2800);
DISPLAY 1.234043 (-1750 2800);
PAINT GREEN (-1750 2800);
DISPLAY INVISIBLE (-1750 2800);
FORCEPROP 1 LAST HDL_TAP TRUE
J 2
(-2075 2725);
DISPLAY 1.234043 (-2075 2725);
PAINT GREEN (-2075 2725);
DISPLAY INVISIBLE (-2075 2725);
FORCEPROP 1 LAST PATH I89
J 2
(-1750 2850);
DISPLAY 0.936170 (-1750 2850);
PAINT GREEN (-1750 2850);
DISPLAY INVISIBLE (-1750 2850);
FORCEADD PVTT_KLM..1
(-1250 2750);
FORCEPROP 3 LASTPIN (-1250 2700) SIG_NAME PVTT_KLM\g
J 0
(-1240 2710);
DISPLAY 0.659574 (-1240 2710);
PAINT MONO (-1240 2710);
DISPLAY INVISIBLE (-1240 2710);
FORCEPROP 1 LAST VOLTAGE 0.6V
J 0
(-1295 2707);
DISPLAY 0.340426 (-1295 2707);
PAINT SKYBLUE (-1295 2707);
DISPLAY INVISIBLE (-1295 2707);
FORCEPROP 2 LAST BOM_COST MEM
J 0
(-1250 2755);
PAINT ORANGE (-1250 2755);
DISPLAY INVISIBLE (-1250 2755);
FORCEPROP 2 LAST CDS_LIB mstr_symbols
J 0
(-1250 2750);
PAINT ORANGE (-1250 2750);
DISPLAY INVISIBLE (-1250 2750);
FORCEPROP 1 LAST BODY_TYPE PLUMBING
J 0
(-1295 2707);
DISPLAY 0.340426 (-1295 2707);
PAINT GREEN (-1295 2707);
DISPLAY INVISIBLE (-1295 2707);
FORCEPROP 1 LAST PATH I9
J 0
(-1200 2775);
DISPLAY 0.872340 (-1200 2775);
PAINT AQUA (-1200 2775);
DISPLAY INVISIBLE (-1200 2775);
FORCEPROP 2 LAST ROOM DDR4_CH_D
J 0
(-1250 2850);
DISPLAY 0.787234 (-1250 2850);
PAINT ORANGE (-1250 2850);
DISPLAY INVISIBLE (-1250 2850);
FORCEPROP 1 LAST HDL_POWER PVTT_KLM
J 1
(-1250 2800);
DISPLAY 0.872340 (-1250 2800);
PAINT GREEN (-1250 2800);
DISPLAY INVISIBLE (-1250 2800);
FORCEADD TAP..6
R 2
(-1750 2800);
FORCEPROP 3 LASTPIN (-1800 2800) SIG_NAME M_M_DQ<20>
J 0
(-1790 2810);
DISPLAY 0.659574 (-1790 2810);
PAINT MONO (-1790 2810);
DISPLAY INVISIBLE (-1790 2810);
FORCEPROP 1 LASTPIN (-1800 2800) BN 20
J 2
(-1750 2810);
DISPLAY 0.617021 (-1750 2810);
PAINT PINK (-1750 2810);
FORCEPROP 2 LAST CDS_LIB mstr_standard
J 2
(-1750 2800);
DISPLAY 0.787234 (-1750 2800);
PAINT MONO (-1750 2800);
DISPLAY INVISIBLE (-1750 2800);
FORCEPROP 1 LAST BODY_TYPE PLUMBING
J 2
(-1750 2750);
DISPLAY 1.234043 (-1750 2750);
PAINT GREEN (-1750 2750);
DISPLAY INVISIBLE (-1750 2750);
FORCEPROP 1 LAST HDL_TAP TRUE
J 2
(-2075 2675);
DISPLAY 1.234043 (-2075 2675);
PAINT GREEN (-2075 2675);
DISPLAY INVISIBLE (-2075 2675);
FORCEPROP 1 LAST PATH I90
J 2
(-1750 2800);
DISPLAY 0.936170 (-1750 2800);
PAINT GREEN (-1750 2800);
DISPLAY INVISIBLE (-1750 2800);
FORCEADD TAP..6
R 2
(-1750 2700);
FORCEPROP 3 LASTPIN (-1800 2700) SIG_NAME M_M_DQ<18>
J 0
(-1790 2710);
DISPLAY 0.659574 (-1790 2710);
PAINT MONO (-1790 2710);
DISPLAY INVISIBLE (-1790 2710);
FORCEPROP 1 LASTPIN (-1800 2700) BN 18
J 2
(-1750 2710);
DISPLAY 0.617021 (-1750 2710);
PAINT PINK (-1750 2710);
FORCEPROP 2 LAST CDS_LIB mstr_standard
J 2
(-1750 2700);
DISPLAY 0.787234 (-1750 2700);
PAINT MONO (-1750 2700);
DISPLAY INVISIBLE (-1750 2700);
FORCEPROP 1 LAST BODY_TYPE PLUMBING
J 2
(-1750 2650);
DISPLAY 1.234043 (-1750 2650);
PAINT GREEN (-1750 2650);
DISPLAY INVISIBLE (-1750 2650);
FORCEPROP 1 LAST HDL_TAP TRUE
J 2
(-2075 2575);
DISPLAY 1.234043 (-2075 2575);
PAINT GREEN (-2075 2575);
DISPLAY INVISIBLE (-2075 2575);
FORCEPROP 1 LAST PATH I91
J 2
(-1750 2700);
DISPLAY 0.936170 (-1750 2700);
PAINT GREEN (-1750 2700);
DISPLAY INVISIBLE (-1750 2700);
FORCEADD TAP..6
R 2
(-1750 2750);
FORCEPROP 3 LASTPIN (-1800 2750) SIG_NAME M_M_DQ<21>
J 0
(-1790 2760);
DISPLAY 0.659574 (-1790 2760);
PAINT MONO (-1790 2760);
DISPLAY INVISIBLE (-1790 2760);
FORCEPROP 1 LASTPIN (-1800 2750) BN 21
J 2
(-1750 2760);
DISPLAY 0.617021 (-1750 2760);
PAINT PINK (-1750 2760);
FORCEPROP 2 LAST CDS_LIB mstr_standard
J 2
(-1750 2750);
DISPLAY 0.787234 (-1750 2750);
PAINT MONO (-1750 2750);
DISPLAY INVISIBLE (-1750 2750);
FORCEPROP 1 LAST BODY_TYPE PLUMBING
J 2
(-1750 2700);
DISPLAY 1.234043 (-1750 2700);
PAINT GREEN (-1750 2700);
DISPLAY INVISIBLE (-1750 2700);
FORCEPROP 1 LAST HDL_TAP TRUE
J 2
(-2075 2625);
DISPLAY 1.234043 (-2075 2625);
PAINT GREEN (-2075 2625);
DISPLAY INVISIBLE (-2075 2625);
FORCEPROP 1 LAST PATH I92
J 2
(-1750 2750);
DISPLAY 0.936170 (-1750 2750);
PAINT GREEN (-1750 2750);
DISPLAY INVISIBLE (-1750 2750);
FORCEADD TAP..6
R 2
(-1750 2400);
FORCEPROP 3 LASTPIN (-1800 2400) SIG_NAME M_M_DQ<12>
J 0
(-1790 2410);
DISPLAY 0.659574 (-1790 2410);
PAINT MONO (-1790 2410);
DISPLAY INVISIBLE (-1790 2410);
FORCEPROP 1 LASTPIN (-1800 2400) BN 12
J 2
(-1750 2410);
DISPLAY 0.617021 (-1750 2410);
PAINT PINK (-1750 2410);
FORCEPROP 2 LAST CDS_LIB mstr_standard
J 2
(-1750 2400);
DISPLAY 0.787234 (-1750 2400);
PAINT MONO (-1750 2400);
DISPLAY INVISIBLE (-1750 2400);
FORCEPROP 1 LAST BODY_TYPE PLUMBING
J 2
(-1750 2350);
DISPLAY 1.234043 (-1750 2350);
PAINT GREEN (-1750 2350);
DISPLAY INVISIBLE (-1750 2350);
FORCEPROP 1 LAST HDL_TAP TRUE
J 2
(-2075 2275);
DISPLAY 1.234043 (-2075 2275);
PAINT GREEN (-2075 2275);
DISPLAY INVISIBLE (-2075 2275);
FORCEPROP 1 LAST PATH I93
J 2
(-1750 2400);
DISPLAY 0.936170 (-1750 2400);
PAINT GREEN (-1750 2400);
DISPLAY INVISIBLE (-1750 2400);
FORCEADD TAP..6
R 2
(-1750 2550);
FORCEPROP 3 LASTPIN (-1800 2550) SIG_NAME M_M_DQ<17>
J 0
(-1790 2560);
DISPLAY 0.659574 (-1790 2560);
PAINT MONO (-1790 2560);
DISPLAY INVISIBLE (-1790 2560);
FORCEPROP 1 LASTPIN (-1800 2550) BN 17
J 2
(-1750 2560);
DISPLAY 0.617021 (-1750 2560);
PAINT PINK (-1750 2560);
FORCEPROP 2 LAST CDS_LIB mstr_standard
J 2
(-1750 2550);
DISPLAY 0.787234 (-1750 2550);
PAINT MONO (-1750 2550);
DISPLAY INVISIBLE (-1750 2550);
FORCEPROP 1 LAST BODY_TYPE PLUMBING
J 2
(-1750 2500);
DISPLAY 1.234043 (-1750 2500);
PAINT GREEN (-1750 2500);
DISPLAY INVISIBLE (-1750 2500);
FORCEPROP 1 LAST HDL_TAP TRUE
J 2
(-2075 2425);
DISPLAY 1.234043 (-2075 2425);
PAINT GREEN (-2075 2425);
DISPLAY INVISIBLE (-2075 2425);
FORCEPROP 1 LAST PATH I94
J 2
(-1750 2550);
DISPLAY 0.936170 (-1750 2550);
PAINT GREEN (-1750 2550);
DISPLAY INVISIBLE (-1750 2550);
FORCEADD TAP..6
R 2
(-1750 2600);
FORCEPROP 3 LASTPIN (-1800 2600) SIG_NAME M_M_DQ<16>
J 0
(-1790 2610);
DISPLAY 0.659574 (-1790 2610);
PAINT MONO (-1790 2610);
DISPLAY INVISIBLE (-1790 2610);
FORCEPROP 1 LASTPIN (-1800 2600) BN 16
J 2
(-1750 2610);
DISPLAY 0.617021 (-1750 2610);
PAINT PINK (-1750 2610);
FORCEPROP 2 LAST CDS_LIB mstr_standard
J 2
(-1750 2600);
DISPLAY 0.787234 (-1750 2600);
PAINT MONO (-1750 2600);
DISPLAY INVISIBLE (-1750 2600);
FORCEPROP 1 LAST BODY_TYPE PLUMBING
J 2
(-1750 2550);
DISPLAY 1.234043 (-1750 2550);
PAINT GREEN (-1750 2550);
DISPLAY INVISIBLE (-1750 2550);
FORCEPROP 1 LAST HDL_TAP TRUE
J 2
(-2075 2475);
DISPLAY 1.234043 (-2075 2475);
PAINT GREEN (-2075 2475);
DISPLAY INVISIBLE (-2075 2475);
FORCEPROP 1 LAST PATH I95
J 2
(-1750 2600);
DISPLAY 0.936170 (-1750 2600);
PAINT GREEN (-1750 2600);
DISPLAY INVISIBLE (-1750 2600);
FORCEADD TAP..6
R 2
(-1750 2450);
FORCEPROP 3 LASTPIN (-1800 2450) SIG_NAME M_M_DQ<15>
J 0
(-1790 2460);
DISPLAY 0.659574 (-1790 2460);
PAINT MONO (-1790 2460);
DISPLAY INVISIBLE (-1790 2460);
FORCEPROP 1 LASTPIN (-1800 2450) BN 15
J 2
(-1750 2460);
DISPLAY 0.617021 (-1750 2460);
PAINT PINK (-1750 2460);
FORCEPROP 2 LAST CDS_LIB mstr_standard
J 2
(-1750 2450);
DISPLAY 0.787234 (-1750 2450);
PAINT MONO (-1750 2450);
DISPLAY INVISIBLE (-1750 2450);
FORCEPROP 1 LAST BODY_TYPE PLUMBING
J 2
(-1750 2400);
DISPLAY 1.234043 (-1750 2400);
PAINT GREEN (-1750 2400);
DISPLAY INVISIBLE (-1750 2400);
FORCEPROP 1 LAST HDL_TAP TRUE
J 2
(-2075 2325);
DISPLAY 1.234043 (-2075 2325);
PAINT GREEN (-2075 2325);
DISPLAY INVISIBLE (-2075 2325);
FORCEPROP 1 LAST PATH I96
J 2
(-1750 2450);
DISPLAY 0.936170 (-1750 2450);
PAINT GREEN (-1750 2450);
DISPLAY INVISIBLE (-1750 2450);
FORCEADD TAP..6
R 2
(-1750 2500);
FORCEPROP 3 LASTPIN (-1800 2500) SIG_NAME M_M_DQ<14>
J 0
(-1790 2510);
DISPLAY 0.659574 (-1790 2510);
PAINT MONO (-1790 2510);
DISPLAY INVISIBLE (-1790 2510);
FORCEPROP 1 LASTPIN (-1800 2500) BN 14
J 2
(-1750 2510);
DISPLAY 0.617021 (-1750 2510);
PAINT PINK (-1750 2510);
FORCEPROP 2 LAST CDS_LIB mstr_standard
J 2
(-1750 2500);
DISPLAY 0.787234 (-1750 2500);
PAINT MONO (-1750 2500);
DISPLAY INVISIBLE (-1750 2500);
FORCEPROP 1 LAST BODY_TYPE PLUMBING
J 2
(-1750 2450);
DISPLAY 1.234043 (-1750 2450);
PAINT GREEN (-1750 2450);
DISPLAY INVISIBLE (-1750 2450);
FORCEPROP 1 LAST HDL_TAP TRUE
J 2
(-2075 2375);
DISPLAY 1.234043 (-2075 2375);
PAINT GREEN (-2075 2375);
DISPLAY INVISIBLE (-2075 2375);
FORCEPROP 1 LAST PATH I97
J 2
(-1750 2500);
DISPLAY 0.936170 (-1750 2500);
PAINT GREEN (-1750 2500);
DISPLAY INVISIBLE (-1750 2500);
FORCEADD TAP..6
R 2
(-1750 2150);
FORCEPROP 3 LASTPIN (-1800 2150) SIG_NAME M_M_DQ<9>
J 0
(-1790 2160);
DISPLAY 0.659574 (-1790 2160);
PAINT MONO (-1790 2160);
DISPLAY INVISIBLE (-1790 2160);
FORCEPROP 1 LASTPIN (-1800 2150) BN 9
J 2
(-1750 2160);
DISPLAY 0.617021 (-1750 2160);
PAINT PINK (-1750 2160);
FORCEPROP 2 LAST CDS_LIB mstr_standard
J 2
(-1750 2150);
DISPLAY 0.787234 (-1750 2150);
PAINT MONO (-1750 2150);
DISPLAY INVISIBLE (-1750 2150);
FORCEPROP 1 LAST BODY_TYPE PLUMBING
J 2
(-1750 2100);
DISPLAY 1.234043 (-1750 2100);
PAINT GREEN (-1750 2100);
DISPLAY INVISIBLE (-1750 2100);
FORCEPROP 1 LAST HDL_TAP TRUE
J 2
(-2075 2025);
DISPLAY 1.234043 (-2075 2025);
PAINT GREEN (-2075 2025);
DISPLAY INVISIBLE (-2075 2025);
FORCEPROP 1 LAST PATH I98
J 2
(-1750 2150);
DISPLAY 0.936170 (-1750 2150);
PAINT GREEN (-1750 2150);
DISPLAY INVISIBLE (-1750 2150);
FORCEADD TAP..6
R 2
(-1750 2250);
FORCEPROP 3 LASTPIN (-1800 2250) SIG_NAME M_M_DQ<11>
J 0
(-1790 2260);
DISPLAY 0.659574 (-1790 2260);
PAINT MONO (-1790 2260);
DISPLAY INVISIBLE (-1790 2260);
FORCEPROP 1 LASTPIN (-1800 2250) BN 11
J 2
(-1750 2260);
DISPLAY 0.617021 (-1750 2260);
PAINT PINK (-1750 2260);
FORCEPROP 2 LAST CDS_LIB mstr_standard
J 2
(-1750 2250);
DISPLAY 0.787234 (-1750 2250);
PAINT MONO (-1750 2250);
DISPLAY INVISIBLE (-1750 2250);
FORCEPROP 1 LAST BODY_TYPE PLUMBING
J 2
(-1750 2200);
DISPLAY 1.234043 (-1750 2200);
PAINT GREEN (-1750 2200);
DISPLAY INVISIBLE (-1750 2200);
FORCEPROP 1 LAST HDL_TAP TRUE
J 2
(-2075 2125);
DISPLAY 1.234043 (-2075 2125);
PAINT GREEN (-2075 2125);
DISPLAY INVISIBLE (-2075 2125);
FORCEPROP 1 LAST PATH I99
J 2
(-1750 2250);
DISPLAY 0.936170 (-1750 2250);
PAINT GREEN (-1750 2250);
DISPLAY INVISIBLE (-1750 2250);
FORCEADD BOM_NOTE..1
(-4975 5250);
FORCEPROP 0 LAST L1 STUFF FOR SKU A & B
J 0
(-5125 5150);
DISPLAY 1.063830 (-5125 5150);
PAINT WHITE (-5125 5150);
FORCEPROP 2 LAST BOM_COST SB
J 0
(-5125 5225);
DISPLAY 1.361702 (-5125 5225);
PAINT ORANGE (-5125 5225);
DISPLAY INVISIBLE (-5125 5225);
FORCEPROP 2 LAST CDS_LIB mstr_symbols
J 0
(-4975 5250);
PAINT ORANGE (-4975 5250);
DISPLAY INVISIBLE (-4975 5250);
FORCEPROP 1 LAST COMMENT_BODY TRUE
J 0
(-4950 5350);
DISPLAY 1.319149 (-4950 5350);
PAINT ORANGE (-4950 5350);
DISPLAY INVISIBLE (-4950 5350);
FORCEPROP 2 LAST ROOM SB_HEADERS
J 0
(-5125 5225);
DISPLAY 1.361702 (-5125 5225);
PAINT ORANGE (-5125 5225);
DISPLAY INVISIBLE (-5125 5225);
FORCEADD INTEL_CORP_BPAGE..1
(2650 500);
FORCEPROP 1 LAST CDS_CON_LAST_MODIFIED Tue Dec 01 11:51:46 2015
J 0
(1225 825);
DISPLAY 0.787234 (1225 825);
PAINT ORANGE (1225 825);
DISPLAY INVISIBLE (1225 825);
FORCEPROP 1 LAST CUSTOM_TXT_CDS <CURRENT_DESIGN_SHEET> OF <TOTAL_DESIGN_SHEETS>
J 0
(2150 525);
PAINT GREEN (2150 525);
FORCEPROP 1 LAST CUSTOM_TXT_CDS <CON_LAST_MODIFIED>
J 0
(725 850);
PAINT GREEN (725 850);
FORCEPROP 2 LAST CUSTOM_TXT_CDS <XR_PAGE_TITLE>
J 0
(-5240 5750);
DISPLAY 0.638298 (-5240 5750);
PAINT PINK (-5240 5750);
DISPLAY INVISIBLE (-5240 5750);
FORCEPROP 1 LAST SCH_ADDRESS3 Santa Clara, CA 95052-8119
J 0
(-1325 525);
DISPLAY 0.617021 (-1325 525);
PAINT GREEN (-1325 525);
FORCEPROP 1 LAST SCH_ADDRESS2 P.O. BOX 58119
J 0
(-1325 575);
DISPLAY 0.617021 (-1325 575);
PAINT GREEN (-1325 575);
FORCEPROP 1 LAST SCH_ADDRESS1 2200 Mission College Blvd.
J 0
(-1325 625);
DISPLAY 0.617021 (-1325 625);
PAINT GREEN (-1325 625);
FORCEPROP 1 LAST SCH_TITLE CPU1 DDR4 CH M DIMM0
J 0
(-5300 550);
DISPLAY 1.212766 (-5300 550);
PAINT WHITE (-5300 550);
FORCEPROP 1 LAST SCH_NUMBER H4694802
J 0
(1350 650);
DISPLAY 1.212766 (1350 650);
PAINT YELLOW (1350 650);
FORCEPROP 1 LAST SCH_DEPT BESD
J 1
(-1800 600);
DISPLAY 1.212766 (-1800 600);
PAINT YELLOW (-1800 600);
FORCEPROP 1 LAST SCH_REV 2.420
J 0
(2400 650);
DISPLAY 0.978723 (2400 650);
PAINT YELLOW (2400 650);
FORCEPROP 2 LAST CDS_LIB mstr_symbols
J 0
(2650 500);
DISPLAY 0.787234 (2650 500);
PAINT MONO (2650 500);
DISPLAY INVISIBLE (2650 500);
FORCEPROP 2 LAST PAGE_BORDER TRUE
J 0
(-5240 5750);
DISPLAY 0.680851 (-5240 5750);
PAINT PINK (-5240 5750);
DISPLAY INVISIBLE (-5240 5750);
FORCEPROP 1 LAST COMMENT_BODY TRUE
J 0
(2660 510);
DISPLAY 0.382979 (2660 510);
PAINT GREEN (2660 510);
DISPLAY INVISIBLE (2660 510);
FORCEPROP 2 LAST CDS_XR_PAGE_TITLE CR-87 : @BASEBOARD_FAB2_LIB.BASEBOARD_FAB2(SCH_1):PAGE87
J 0
(-5240 5750);
DISPLAY 0.638298 (-5240 5750);
PAINT PINK (-5240 5750);
DISPLAY INVISIBLE (-5240 5750);
WIRE 17 -1 (750 5175)(750 5200);
WIRE 17 -1 (750 5075)(750 5175);
WIRE 17 -1 (1550 5200)(750 5200);
FORCEPROP 2 LAST SIG_NAME M_M_DQS_DP<17:0>
J 0
(1000 5210);
DISPLAY 0.617021 (1000 5210);
PAINT ORANGE (1000 5210);
WIRE 17 -1 (950 4425)(950 4525);
WIRE 17 -1 (950 4325)(950 4425);
WIRE 17 -1 (950 4525)(950 4625);
WIRE 17 -1 (950 4625)(950 4725);
WIRE 17 -1 (950 4225)(950 4325);
WIRE 17 -1 (950 4125)(950 4225);
WIRE 17 -1 (950 4725)(950 4825);
WIRE 17 -1 (950 4825)(950 4925);
WIRE 17 -1 (950 4025)(950 4125);
WIRE 17 -1 (950 3925)(950 4025);
WIRE 17 -1 (950 4925)(950 5025);
WIRE 17 -1 (950 5025)(950 5125);
WIRE 17 -1 (950 3825)(950 3925);
WIRE 17 -1 (950 3725)(950 3825);
WIRE 17 -1 (950 5125)(950 5150);
WIRE 17 -1 (1550 5150)(950 5150);
FORCEPROP 2 LAST SIG_NAME M_M_DQS_DN<17:0>
J 0
(1000 5160);
DISPLAY 0.617021 (1000 5160);
PAINT ORANGE (1000 5160);
WIRE 17 -1 (750 4475)(750 4575);
WIRE 17 -1 (750 4375)(750 4475);
WIRE 17 -1 (750 4575)(750 4675);
WIRE 17 -1 (750 4675)(750 4775);
WIRE 17 -1 (750 4275)(750 4375);
WIRE 17 -1 (750 4175)(750 4275);
WIRE 17 -1 (750 4775)(750 4875);
WIRE 17 -1 (750 4875)(750 4975);
WIRE 17 -1 (750 4075)(750 4175);
WIRE 17 -1 (750 3975)(750 4075);
WIRE 17 -1 (750 4975)(750 5075);
WIRE 17 -1 (750 3875)(750 3975);
WIRE 17 -1 (750 3775)(750 3875);
WIRE 17 -1 (950 3625)(950 3725);
WIRE 17 -1 (950 3525)(950 3625);
WIRE 17 -1 (950 3425)(950 3525);
WIRE 17 -1 (750 3675)(750 3775);
WIRE 17 -1 (750 3575)(750 3675);
WIRE 17 -1 (750 3475)(750 3575);
WIRE 17 -1 (-1700 4950)(-1700 4925);
WIRE 17 -1 (-1250 4950)(-1700 4950);
FORCEPROP 2 LAST SIG_NAME M_M_DQ<63:0>
J 0
(-1660 4960);
DISPLAY 0.617021 (-1660 4960);
PAINT ORANGE (-1660 4960);
WIRE 17 -1 (-1700 4775)(-1700 4825);
WIRE 17 -1 (-1700 4725)(-1700 4775);
WIRE 17 -1 (-1700 4825)(-1700 4875);
WIRE 17 -1 (-1700 4875)(-1700 4925);
WIRE 17 -1 (-1700 4675)(-1700 4725);
WIRE 17 -1 (-1700 4625)(-1700 4675);
WIRE 17 -1 (-1700 4575)(-1700 4625);
WIRE 17 -1 (-1700 4525)(-1700 4575);
WIRE 17 -1 (-1700 4475)(-1700 4525);
WIRE 17 -1 (-1700 4425)(-1700 4475);
WIRE 17 -1 (-1700 4375)(-1700 4425);
WIRE 17 -1 (-1700 4325)(-1700 4375);
WIRE 17 -1 (-1700 4275)(-1700 4325);
WIRE 17 -1 (-1700 4225)(-1700 4275);
WIRE 17 -1 (-1700 4175)(-1700 4225);
WIRE 17 -1 (-1700 4125)(-1700 4175);
WIRE 17 -1 (-1700 4075)(-1700 4125);
WIRE 17 -1 (-1700 4025)(-1700 4075);
WIRE 17 -1 (-1700 3975)(-1700 4025);
WIRE 17 -1 (-1700 3925)(-1700 3975);
WIRE 17 -1 (-1700 3875)(-1700 3925);
WIRE 17 -1 (-1700 3825)(-1700 3875);
WIRE 17 -1 (-1700 3775)(-1700 3825);
WIRE 17 -1 (-1700 3725)(-1700 3775);
WIRE 17 -1 (-1700 3675)(-1700 3725);
WIRE 17 -1 (-1700 3625)(-1700 3675);
WIRE 17 -1 (-1700 3575)(-1700 3625);
WIRE 17 -1 (-1700 3525)(-1700 3575);
WIRE 17 -1 (-1700 3475)(-1700 3525);
WIRE 17 -1 (-1700 3425)(-1700 3475);
WIRE 17 -1 (-1700 3375)(-1700 3425);
WIRE 17 -1 (-1700 3325)(-1700 3375);
WIRE 17 -1 (-1700 3275)(-1700 3325);
WIRE 17 -1 (-3300 4125)(-3300 4175);
WIRE 17 -1 (-3300 4075)(-3300 4125);
WIRE 17 -1 (-3300 4175)(-3300 4225);
WIRE 17 -1 (-3300 4225)(-3300 4275);
WIRE 17 -1 (-3300 4275)(-3300 4325);
WIRE 17 -1 (-3300 4325)(-3300 4375);
WIRE 17 -1 (-3300 4375)(-3300 4425);
WIRE 17 -1 (-3300 4425)(-3300 4475);
WIRE 17 -1 (-3300 4475)(-3300 4525);
WIRE 17 -1 (-3300 4525)(-3300 4575);
WIRE 17 -1 (-3300 4575)(-3300 4625);
WIRE 17 -1 (-3300 4625)(-3300 4675);
WIRE 17 -1 (-3300 4675)(-3300 4725);
WIRE 17 -1 (-3300 4725)(-3300 4775);
WIRE 17 -1 (-3300 4775)(-3300 4825);
WIRE 17 -1 (-3300 4825)(-3300 4875);
WIRE 17 -1 (-3300 4875)(-3300 4925);
WIRE 17 -1 (-3300 4925)(-3300 4950);
WIRE 17 -1 (-3800 4950)(-3300 4950);
FORCEPROP 2 LAST SIG_NAME M_M_MA<17:0>
J 0
(-3750 4960);
DISPLAY 0.617021 (-3750 4960);
PAINT ORANGE (-3750 4960);
WIRE 17 -1 (-1700 3225)(-1700 3275);
WIRE 17 -1 (-1700 3175)(-1700 3225);
WIRE 17 -1 (-1700 3125)(-1700 3175);
WIRE 17 -1 (-1700 3075)(-1700 3125);
WIRE 17 -1 (-1700 3025)(-1700 3075);
WIRE 17 -1 (-1700 2975)(-1700 3025);
WIRE 17 -1 (-1700 2925)(-1700 2975);
WIRE 17 -1 (-1700 2875)(-1700 2925);
WIRE 17 -1 (-1700 2825)(-1700 2875);
WIRE 17 -1 (-1700 2775)(-1700 2825);
WIRE 17 -1 (-1700 2725)(-1700 2775);
WIRE 17 -1 (-1700 2675)(-1700 2725);
WIRE 17 -1 (-1700 2625)(-1700 2675);
WIRE 17 -1 (-1700 2575)(-1700 2625);
WIRE 17 -1 (-1700 2525)(-1700 2575);
WIRE 17 -1 (-1700 2475)(-1700 2525);
WIRE 17 -1 (-1700 2425)(-1700 2475);
WIRE 17 -1 (-1700 2375)(-1700 2425);
WIRE 17 -1 (-1700 2325)(-1700 2375);
WIRE 17 -1 (-1700 2275)(-1700 2325);
WIRE 17 -1 (-1700 2225)(-1700 2275);
WIRE 17 -1 (-1700 2175)(-1700 2225);
WIRE 17 -1 (-1700 2125)(-1700 2175);
WIRE 17 -1 (-1700 2075)(-1700 2125);
WIRE 17 -1 (-1700 2025)(-1700 2075);
WIRE 17 -1 (-1700 1975)(-1700 2025);
WIRE 17 -1 (-1700 1925)(-1700 1975);
WIRE 17 -1 (-1700 1875)(-1700 1925);
WIRE 17 -1 (-1700 1825)(-1700 1875);
WIRE 17 -1 (-1700 1775)(-1700 1825);
WIRE 17 -1 (-3300 3425)(-3300 3450);
WIRE 17 -1 (-3300 3375)(-3300 3425);
WIRE 17 -1 (-3300 3450)(-3800 3450);
FORCEPROP 2 LAST SIG_NAME M_M_CS_N<7:0>
J 0
(-3775 3460);
DISPLAY 0.617021 (-3775 3460);
PAINT ORANGE (-3775 3460);
WIRE 17 -1 (-3500 3675)(-3500 3725);
WIRE 17 -1 (-3500 3675)(-3500 3575);
WIRE 17 -1 (-3500 3725)(-3800 3725);
FORCEPROP 2 LAST SIG_NAME M_M_CLK_DN<3:0>
J 0
(-3800 3735);
DISPLAY 0.617021 (-3800 3735);
PAINT ORANGE (-3800 3735);
WIRE 17 -1 (-3300 3625)(-3300 3725);
WIRE 17 -1 (-3300 3725)(-3300 3775);
WIRE 17 -1 (-3300 3775)(-3800 3775);
FORCEPROP 2 LAST SIG_NAME M_M_CLK_DP<3:0>
J 0
(-3800 3785);
DISPLAY 0.617021 (-3800 3785);
PAINT ORANGE (-3800 3785);
WIRE 17 -1 (-3300 4000)(-3300 3975);
WIRE 17 -1 (-3300 4000)(-3800 4000);
FORCEPROP 2 LAST SIG_NAME M_M_BA<1:0>
J 0
(-3775 4010);
DISPLAY 0.617021 (-3775 4010);
PAINT ORANGE (-3775 4010);
WIRE 17 -1 (-3300 3325)(-3300 3375);
WIRE 17 -1 (-3300 3275)(-3300 3325);
WIRE 17 -1 (-3300 2825)(-3300 2875);
WIRE 17 -1 (-3300 2775)(-3300 2825);
WIRE 17 -1 (-3300 2875)(-3300 2900);
WIRE 17 -1 (-3300 2900)(-3800 2900);
FORCEPROP 2 LAST SIG_NAME M_M_ECC<7:0>
J 0
(-3775 2910);
DISPLAY 0.617021 (-3775 2910);
PAINT ORANGE (-3775 2910);
WIRE 17 -1 (-3300 2725)(-3300 2775);
WIRE 17 -1 (-3300 2675)(-3300 2725);
WIRE 17 -1 (-3300 2625)(-3300 2675);
WIRE 17 -1 (-3300 2575)(-3300 2625);
WIRE 17 -1 (-3300 2525)(-3300 2575);
WIRE 17 -1 (-3300 3175)(-3300 3225);
WIRE 17 -1 (-3300 3125)(-3300 3175);
WIRE 17 -1 (-3300 3225)(-3800 3225);
FORCEPROP 2 LAST SIG_NAME M_M_CKE<3:0>
J 0
(-3775 3235);
DISPLAY 0.617021 (-3775 3235);
PAINT ORANGE (-3775 3235);
WIRE 17 -1 (-3300 3825)(-3300 3875);
WIRE 17 -1 (-3300 3875)(-3300 3900);
WIRE 17 -1 (-3300 3900)(-3800 3900);
FORCEPROP 2 LAST SIG_NAME M_M_BG<1:0>
J 0
(-3775 3910);
DISPLAY 0.617021 (-3775 3910);
PAINT ORANGE (-3775 3910);
WIRE 17 -1 (-3300 3925)(-3300 3975);
WIRE 17 -1 (-3300 2975)(-3300 3025);
WIRE 17 -1 (-3300 3025)(-3300 3100);
WIRE 17 -1 (-3300 3100)(-3800 3100);
FORCEPROP 2 LAST SIG_NAME M_M_ODT<3:0>
J 0
(-3775 3110);
DISPLAY 0.617021 (-3775 3110);
PAINT ORANGE (-3775 3110);
WIRE 16 -1 (-1100 1200)(-900 1200);
WIRE 16 -1 (-1100 1200)(-1100 1250);
WIRE 16 -1 (-1100 1250)(-900 1250);
WIRE 16 -1 (-1100 1250)(-1100 1300);
WIRE 16 -1 (-1100 1300)(-900 1300);
WIRE 16 -1 (-1100 1300)(-1100 1350);
WIRE 16 -1 (-1100 1350)(-900 1350);
WIRE 16 -1 (-1100 1350)(-1100 1400);
WIRE 16 -1 (-1100 1400)(-900 1400);
WIRE 16 -1 (-1100 1400)(-1100 1450);
WIRE 16 -1 (-1100 1450)(-900 1450);
WIRE 16 -1 (-1100 1450)(-1100 1500);
WIRE 16 -1 (-1100 1500)(-900 1500);
WIRE 16 -1 (-1100 1500)(-1100 1550);
WIRE 16 -1 (-1100 1550)(-900 1550);
WIRE 16 -1 (-1100 1550)(-1100 1600);
WIRE 16 -1 (-1100 1600)(-900 1600);
WIRE 16 -1 (-1100 1600)(-1100 1650);
WIRE 16 -1 (-1100 1650)(-900 1650);
WIRE 16 -1 (-1100 1650)(-1100 1700);
WIRE 16 -1 (-1100 1700)(-900 1700);
WIRE 16 -1 (-1100 1700)(-1100 1750);
WIRE 16 -1 (-1100 1750)(-900 1750);
WIRE 16 -1 (-1100 1750)(-1100 1800);
WIRE 16 -1 (-1100 1800)(-900 1800);
WIRE 16 -1 (-1100 1800)(-1100 1850);
WIRE 16 -1 (-1100 1850)(-900 1850);
WIRE 16 -1 (-1100 1850)(-1100 1900);
WIRE 16 -1 (-1100 1900)(-900 1900);
WIRE 16 -1 (-1100 1900)(-1100 1950);
WIRE 16 -1 (-1100 1950)(-900 1950);
WIRE 16 -1 (-1100 1950)(-1100 2000);
WIRE 16 -1 (-1100 2000)(-1100 2050);
WIRE 16 -1 (-1100 2000)(-900 2000);
WIRE 16 -1 (-1100 2050)(-900 2050);
WIRE 16 -1 (-1100 2050)(-1100 2100);
WIRE 16 -1 (-1100 2100)(-900 2100);
WIRE 16 -1 (-1100 2100)(-1100 2150);
WIRE 16 -1 (-1100 2150)(-900 2150);
WIRE 16 -1 (-1100 2150)(-1100 2200);
WIRE 16 -1 (-1100 2200)(-900 2200);
WIRE 16 -1 (-1100 2200)(-1100 2250);
WIRE 16 -1 (-1100 2250)(-900 2250);
WIRE 16 -1 (-1100 2250)(-1100 2300);
WIRE 16 -1 (-1100 2300)(-900 2300);
WIRE 16 -1 (-1100 2300)(-1100 2350);
WIRE 16 -1 (-1100 2350)(-900 2350);
WIRE 16 -1 (-1100 2350)(-1100 2400);
WIRE 16 -1 (-1100 2400)(-900 2400);
WIRE 16 -1 (-1100 2400)(-1100 2450);
WIRE 16 -1 (-1100 2450)(-900 2450);
WIRE 16 -1 (-1450 2450)(-1100 2450);
WIRE 16 -1 (-1450 2550)(-1450 2450);
WIRE 16 -1 (2500 3600)(2300 3600);
WIRE 16 -1 (2500 3550)(2500 3600);
WIRE 16 -1 (2500 3500)(2500 3550);
WIRE 16 -1 (2500 3550)(2300 3550);
WIRE 16 -1 (2500 3450)(2500 3500);
WIRE 16 -1 (2500 3500)(2300 3500);
WIRE 16 -1 (2500 3400)(2500 3450);
WIRE 16 -1 (2500 3450)(2300 3450);
WIRE 16 -1 (2500 3350)(2500 3400);
WIRE 16 -1 (2500 3400)(2300 3400);
WIRE 16 -1 (2500 3300)(2500 3350);
WIRE 16 -1 (2500 3350)(2300 3350);
WIRE 16 -1 (2500 3250)(2500 3300);
WIRE 16 -1 (2500 3300)(2300 3300);
WIRE 16 -1 (2500 3200)(2500 3250);
WIRE 16 -1 (2500 3250)(2300 3250);
WIRE 16 -1 (2500 3150)(2500 3200);
WIRE 16 -1 (2500 3200)(2300 3200);
WIRE 16 -1 (2500 3100)(2500 3150);
WIRE 16 -1 (2500 3150)(2300 3150);
WIRE 16 -1 (2500 3100)(2300 3100);
WIRE 16 -1 (2500 3050)(2500 3100);
WIRE 16 -1 (2500 3000)(2500 3050);
WIRE 16 -1 (2500 3050)(2300 3050);
WIRE 16 -1 (2500 2950)(2500 3000);
WIRE 16 -1 (2500 3000)(2300 3000);
WIRE 16 -1 (2500 2900)(2500 2950);
WIRE 16 -1 (2500 2950)(2300 2950);
WIRE 16 -1 (2500 2850)(2500 2900);
WIRE 16 -1 (2500 2900)(2300 2900);
WIRE 16 -1 (2500 2800)(2500 2850);
WIRE 16 -1 (2500 2850)(2300 2850);
WIRE 16 -1 (2500 2750)(2500 2800);
WIRE 16 -1 (2500 2800)(2300 2800);
WIRE 16 -1 (2500 2700)(2500 2750);
WIRE 16 -1 (2500 2750)(2300 2750);
WIRE 16 -1 (2500 2650)(2500 2700);
WIRE 16 -1 (2500 2700)(2300 2700);
WIRE 16 -1 (2500 2600)(2500 2650);
WIRE 16 -1 (2500 2650)(2300 2650);
WIRE 16 -1 (2500 2600)(2300 2600);
WIRE 16 -1 (2500 2550)(2500 2600);
WIRE 16 -1 (2500 2500)(2500 2550);
WIRE 16 -1 (2500 2550)(2300 2550);
WIRE 16 -1 (2500 2450)(2500 2500);
WIRE 16 -1 (2500 2500)(2300 2500);
WIRE 16 -1 (2500 2400)(2500 2450);
WIRE 16 -1 (2500 2450)(2300 2450);
WIRE 16 -1 (2500 2350)(2500 2400);
WIRE 16 -1 (2500 2400)(2300 2400);
WIRE 16 -1 (2500 2300)(2500 2350);
WIRE 16 -1 (2500 2350)(2300 2350);
WIRE 16 -1 (2500 2250)(2500 2300);
WIRE 16 -1 (2500 2300)(2300 2300);
WIRE 16 -1 (2500 2200)(2500 2250);
WIRE 16 -1 (2500 2250)(2300 2250);
WIRE 16 -1 (2500 2150)(2500 2200);
WIRE 16 -1 (2500 2200)(2300 2200);
WIRE 16 -1 (2500 2100)(2500 2150);
WIRE 16 -1 (2500 2150)(2300 2150);
WIRE 16 -1 (2500 2050)(2500 2100);
WIRE 16 -1 (2500 2100)(2300 2100);
WIRE 16 -1 (2500 2050)(2300 2050);
WIRE 16 -1 (2500 2000)(2500 2050);
WIRE 16 -1 (2500 1950)(2500 2000);
WIRE 16 -1 (2500 2000)(2300 2000);
WIRE 16 -1 (2500 1900)(2500 1950);
WIRE 16 -1 (2500 1950)(2300 1950);
WIRE 16 -1 (2500 1850)(2500 1900);
WIRE 16 -1 (2500 1900)(2300 1900);
WIRE 16 -1 (2500 1800)(2500 1850);
WIRE 16 -1 (2500 1850)(2300 1850);
WIRE 16 -1 (2500 1750)(2500 1800);
WIRE 16 -1 (2500 1800)(2300 1800);
WIRE 16 -1 (2500 1700)(2500 1750);
WIRE 16 -1 (2500 1750)(2300 1750);
WIRE 16 -1 (2500 1650)(2500 1700);
WIRE 16 -1 (2500 1700)(2300 1700);
WIRE 16 -1 (2500 1600)(2500 1650);
WIRE 16 -1 (2500 1650)(2300 1650);
WIRE 16 -1 (2500 1550)(2500 1600);
WIRE 16 -1 (2500 1600)(2300 1600);
WIRE 16 -1 (2500 1550)(2300 1550);
WIRE 16 -1 (2500 1500)(2500 1550);
WIRE 16 -1 (2500 1450)(2500 1500);
WIRE 16 -1 (2500 1500)(2300 1500);
WIRE 16 -1 (2500 1400)(2500 1450);
WIRE 16 -1 (2500 1450)(2300 1450);
WIRE 16 -1 (2500 1350)(2500 1400);
WIRE 16 -1 (2500 1400)(2300 1400);
WIRE 16 -1 (2500 1300)(2500 1350);
WIRE 16 -1 (2500 1350)(2300 1350);
WIRE 16 -1 (2500 1200)(2500 1300);
WIRE 16 -1 (2500 1300)(2300 1300);
WIRE 16 -1 (-3000 1950)(-3200 1950);
WIRE 16 -1 (-3200 1950)(-3200 2000);
WIRE 16 -1 (-3200 2000)(-3000 2000);
WIRE 16 -1 (-5000 2000)(-3200 2000);
WIRE 16 -1 (-5000 2000)(-5000 1900);
WIRE 16 -1 (-4650 1450)(-4650 1350);
WIRE 16 -1 (-1100 2700)(-900 2700);
WIRE 16 -1 (-1100 2750)(-1100 2700);
WIRE 16 -1 (-1100 2750)(-900 2750);
WIRE 16 -1 (-1100 2800)(-1100 2750);
WIRE 16 -1 (-1100 2800)(-900 2800);
WIRE 16 -1 (-1100 2800)(-1100 2850);
WIRE 16 -1 (-1100 2850)(-900 2850);
WIRE 16 -1 (-1100 2900)(-1100 2850);
WIRE 16 -1 (-1100 2900)(-900 2900);
WIRE 16 -1 (-1100 3000)(-1100 2900);
WIRE 16 -1 (-3000 2050)(-3200 2050);
WIRE 16 -1 (-3200 2050)(-3200 2100);
WIRE 16 -1 (-3000 2100)(-3200 2100);
WIRE 16 -1 (-3200 2100)(-5000 2100);
WIRE 16 -1 (-5000 2100)(-5000 2200);
WIRE 16 -1 (100 2850)(300 2850);
WIRE 16 -1 (300 2850)(300 2900);
WIRE 16 -1 (100 2900)(300 2900);
WIRE 16 -1 (300 2900)(300 2975);
WIRE 16 -1 (1100 3600)(1300 3600);
WIRE 16 -1 (1100 3550)(1100 3600);
WIRE 16 -1 (1100 3550)(1300 3550);
WIRE 16 -1 (1100 3500)(1100 3550);
WIRE 16 -1 (1100 3500)(1300 3500);
WIRE 16 -1 (1100 3450)(1100 3500);
WIRE 16 -1 (1100 3450)(1300 3450);
WIRE 16 -1 (1100 3400)(1100 3450);
WIRE 16 -1 (1100 3400)(1300 3400);
WIRE 16 -1 (1100 3350)(1100 3400);
WIRE 16 -1 (1100 3350)(1300 3350);
WIRE 16 -1 (1100 3300)(1100 3350);
WIRE 16 -1 (1100 3300)(1300 3300);
WIRE 16 -1 (1100 3250)(1100 3300);
WIRE 16 -1 (1100 3250)(1300 3250);
WIRE 16 -1 (1100 3200)(1100 3250);
WIRE 16 -1 (1100 3200)(1300 3200);
WIRE 16 -1 (1100 3150)(1100 3200);
WIRE 16 -1 (1100 3150)(1300 3150);
WIRE 16 -1 (1100 3100)(1100 3150);
WIRE 16 -1 (1100 3100)(1300 3100);
WIRE 16 -1 (1100 3050)(1100 3100);
WIRE 16 -1 (1100 3050)(1300 3050);
WIRE 16 -1 (1100 3000)(1100 3050);
WIRE 16 -1 (1100 3000)(1300 3000);
WIRE 16 -1 (1100 2950)(1100 3000);
WIRE 16 -1 (1100 2950)(1300 2950);
WIRE 16 -1 (1100 2900)(1100 2950);
WIRE 16 -1 (1100 2900)(1300 2900);
WIRE 16 -1 (1100 2850)(1100 2900);
WIRE 16 -1 (1100 2850)(1300 2850);
WIRE 16 -1 (1100 2800)(1100 2850);
WIRE 16 -1 (1100 2800)(1300 2800);
WIRE 16 -1 (1100 2750)(1100 2800);
WIRE 16 -1 (1100 2750)(1300 2750);
WIRE 16 -1 (1100 2700)(1100 2750);
WIRE 16 -1 (1100 2700)(1300 2700);
WIRE 16 -1 (1100 2650)(1100 2700);
WIRE 16 -1 (1100 2650)(1300 2650);
WIRE 16 -1 (1100 2600)(1100 2650);
WIRE 16 -1 (1100 2600)(1300 2600);
WIRE 16 -1 (1100 2550)(1100 2600);
WIRE 16 -1 (1100 2550)(1300 2550);
WIRE 16 -1 (1100 2500)(1100 2550);
WIRE 16 -1 (1100 2500)(1300 2500);
WIRE 16 -1 (1100 2450)(1100 2500);
WIRE 16 -1 (1100 2450)(1300 2450);
WIRE 16 -1 (1100 2400)(1100 2450);
WIRE 16 -1 (1100 2400)(1300 2400);
WIRE 16 -1 (1100 2350)(1100 2400);
WIRE 16 -1 (1100 2350)(1300 2350);
WIRE 16 -1 (1100 2300)(1100 2350);
WIRE 16 -1 (1100 2300)(1300 2300);
WIRE 16 -1 (1100 2250)(1100 2300);
WIRE 16 -1 (1100 2250)(1300 2250);
WIRE 16 -1 (1100 2200)(1100 2250);
WIRE 16 -1 (1100 2200)(1300 2200);
WIRE 16 -1 (1100 2150)(1100 2200);
WIRE 16 -1 (1100 2150)(1300 2150);
WIRE 16 -1 (1100 2100)(1100 2150);
WIRE 16 -1 (1100 2100)(1300 2100);
WIRE 16 -1 (1100 2050)(1100 2100);
WIRE 16 -1 (1100 2050)(1300 2050);
WIRE 16 -1 (1100 2000)(1100 2050);
WIRE 16 -1 (1100 2000)(1300 2000);
WIRE 16 -1 (1100 1950)(1100 2000);
WIRE 16 -1 (1100 1950)(1300 1950);
WIRE 16 -1 (1100 1900)(1100 1950);
WIRE 16 -1 (1100 1900)(1300 1900);
WIRE 16 -1 (1100 1850)(1100 1900);
WIRE 16 -1 (1100 1850)(1300 1850);
WIRE 16 -1 (1100 1800)(1100 1850);
WIRE 16 -1 (1100 1800)(1300 1800);
WIRE 16 -1 (1100 1750)(1100 1800);
WIRE 16 -1 (1100 1750)(1300 1750);
WIRE 16 -1 (1100 1700)(1100 1750);
WIRE 16 -1 (1100 1700)(1300 1700);
WIRE 16 -1 (1100 1650)(1100 1700);
WIRE 16 -1 (1100 1650)(1300 1650);
WIRE 16 -1 (1100 1600)(1100 1650);
WIRE 16 -1 (1100 1600)(1300 1600);
WIRE 16 -1 (1100 1550)(1100 1600);
WIRE 16 -1 (1100 1550)(1300 1550);
WIRE 16 -1 (1100 1500)(1100 1550);
WIRE 16 -1 (1100 1500)(1300 1500);
WIRE 16 -1 (1100 1450)(1100 1500);
WIRE 16 -1 (1100 1450)(1300 1450);
WIRE 16 -1 (1100 1400)(1100 1450);
WIRE 16 -1 (1100 1400)(1300 1400);
WIRE 16 -1 (1100 1350)(1100 1400);
WIRE 16 -1 (1100 1350)(1300 1350);
WIRE 16 -1 (1100 1300)(1100 1350);
WIRE 16 -1 (1100 1300)(1300 1300);
WIRE 16 -1 (1100 1200)(1100 1300);
WIRE 16 -1 (-1100 2550)(-900 2550);
WIRE 16 -1 (-1100 2550)(-1100 2600);
WIRE 16 -1 (-1100 2600)(-900 2600);
WIRE 16 -1 (-1250 2600)(-1100 2600);
WIRE 16 -1 (-1250 2700)(-1250 2600);
WIRE 16 -1 (-3000 1750)(-4650 1750);
FORCEPROP 2 LAST SIG_NAME M_M_VREF
J 0
(-3750 1760);
DISPLAY 0.617021 (-3750 1760);
PAINT ORANGE (-3750 1760);
WIRE 16 -1 (-4650 1750)(-4650 1650);
WIRE 16 -1 (-4650 1750)(-4750 1750);
WIRE 16 -1 (-3850 1600)(-3000 1600);
FORCEPROP 2 LAST SIG_NAME TP_CH_M_DIMM_M0_RFU_1
J 0
(-3800 1610);
DISPLAY 0.617021 (-3800 1610);
PAINT ORANGE (-3800 1610);
FORCEPROP 2 LASTPROP $XRERR UNIQUE?
J 0
(-4090 1600);
DISPLAY 0.638298 (-4090 1600);
PAINT MONO (-4090 1600);
DISPLAY INVISIBLE (-4090 1600);
WIRE 16 -1 (-3850 1550)(-3000 1550);
FORCEPROP 2 LAST SIG_NAME TP_CH_M_DIMM_M0_RFU_0
J 0
(-3800 1560);
DISPLAY 0.617021 (-3800 1560);
PAINT ORANGE (-3800 1560);
FORCEPROP 2 LASTPROP $XRERR UNIQUE?
J 0
(-4090 1550);
DISPLAY 0.638298 (-4090 1550);
PAINT MONO (-4090 1550);
DISPLAY INVISIBLE (-4090 1550);
WIRE 16 -1 (-3850 1650)(-3000 1650);
FORCEPROP 2 LAST SIG_NAME TP_CH_M_DIMM_M0_RFU_2
J 0
(-3800 1660);
DISPLAY 0.617021 (-3800 1660);
PAINT ORANGE (-3800 1660);
FORCEPROP 2 LASTPROP $XRERR UNIQUE?
J 0
(-4090 1650);
DISPLAY 0.638298 (-4090 1650);
PAINT MONO (-4090 1650);
DISPLAY INVISIBLE (-4090 1650);
WIRE 16 -1 (-3000 1900)(-3800 1900);
WIRE 16 -1 (-3800 1850)(-3000 1850);
FORCEPROP 2 LAST SIG_NAME SMB_DDR_KLM_VPP_SCL
J 0
(-3760 1860);
DISPLAY 0.617021 (-3760 1860);
PAINT ORANGE (-3760 1860);
WIRE 16 -1 (-3850 1450)(-3000 1450);
FORCEPROP 2 LAST SIG_NAME FM_ADR_COMPLETE_KLM_N
J 0
(-3800 1460);
DISPLAY 0.617021 (-3800 1460);
PAINT ORANGE (-3800 1460);
WIRE 16 -1 (-3000 2350)(-3400 2350);
WIRE 16 -1 (-3400 2350)(-3400 2800);
WIRE 16 -1 (-3400 2800)(-3800 2800);
FORCEPROP 2 LAST SIG_NAME M_KLM_RST_N
J 0
(-3775 2810);
DISPLAY 0.617021 (-3775 2810);
PAINT ORANGE (-3775 2810);
WIRE 16 -1 (-3000 2400)(-3350 2400);
WIRE 16 -1 (-3350 2400)(-3350 2850);
WIRE 16 -1 (-3350 2850)(-3800 2850);
FORCEPROP 2 LAST SIG_NAME M_M_PAR
J 0
(-3775 2860);
DISPLAY 0.617021 (-3775 2860);
PAINT ORANGE (-3775 2860);
WIRE 16 -1 (-3450 2300)(-3000 2300);
WIRE 16 -1 (-3450 2300)(-3450 2600);
WIRE 16 -1 (-4175 2600)(-3450 2600);
FORCEPROP 2 LAST SIG_NAME FM_DIMM_EVENT_COD_N
J 0
(-4151 2618);
DISPLAY 0.617021 (-4151 2618);
PAINT ORANGE (-4151 2618);
WIRE 16 -1 (-3150 3450)(-3000 3450);
WIRE 16 -1 (-3150 3500)(-3150 3450);
WIRE 16 -1 (-3150 3500)(-3800 3500);
FORCEPROP 2 LAST SIG_NAME M_M_C<2>
J 0
(-3775 3510);
DISPLAY 0.617021 (-3775 3510);
PAINT ORANGE (-3775 3510);
WIRE 16 -1 (-3000 3250)(-3200 3250);
WIRE 16 -1 (-3000 3100)(-3200 3100);
WIRE 16 -1 (-3000 3000)(-3200 3000);
WIRE 16 -1 (-3000 2950)(-3200 2950);
WIRE 16 -1 (-3000 2850)(-3200 2850);
WIRE 16 -1 (-3000 3900)(-3200 3900);
WIRE 16 -1 (-3000 3850)(-3200 3850);
WIRE 16 -1 (-3000 3800)(-3200 3800);
WIRE 16 -1 (-3000 3700)(-3200 3700);
WIRE 16 -1 (-3000 3150)(-3200 3150);
WIRE 16 -1 (-3000 2500)(-3200 2500);
WIRE 16 -1 (-3000 2550)(-3200 2550);
WIRE 16 -1 (-3000 2600)(-3200 2600);
WIRE 16 -1 (-3000 2650)(-3200 2650);
WIRE 16 -1 (-3000 2700)(-3200 2700);
WIRE 16 -1 (-3000 2750)(-3200 2750);
WIRE 16 -1 (-3000 2800)(-3200 2800);
WIRE 16 -1 (-3000 4050)(-3200 4050);
WIRE 16 -1 (-3000 3300)(-3200 3300);
WIRE 16 -1 (-3000 3350)(-3200 3350);
WIRE 16 -1 (-3000 3950)(-3200 3950);
WIRE 16 -1 (-3000 3550)(-3400 3550);
WIRE 16 -1 (-3000 3600)(-3200 3600);
WIRE 16 -1 (-3000 3650)(-3400 3650);
WIRE 16 -1 (-3000 3400)(-3200 3400);
WIRE 16 -1 (-3000 2250)(-4025 2250);
FORCEPROP 2 LAST SIG_NAME M_M_ALERT_N
J 0
(-3975 2260);
DISPLAY 0.617021 (-3975 2260);
PAINT ORANGE (-3975 2260);
WIRE 16 -1 (-3000 2200)(-4000 2200);
FORCEPROP 2 LAST SIG_NAME M_M_ACT_N
J 0
(-3950 2210);
DISPLAY 0.617021 (-3950 2210);
PAINT ORANGE (-3950 2210);
WIRE 16 -1 (-1800 1750)(-2000 1750);
WIRE 16 -1 (-1800 2000)(-2000 2000);
WIRE 16 -1 (-1800 1950)(-2000 1950);
WIRE 16 -1 (-1800 1900)(-2000 1900);
WIRE 16 -1 (-1800 1850)(-2000 1850);
WIRE 16 -1 (-1800 1800)(-2000 1800);
WIRE 16 -1 (-1800 2050)(-2000 2050);
WIRE 16 -1 (-1800 2100)(-2000 2100);
WIRE 16 -1 (-1800 2150)(-2000 2150);
WIRE 16 -1 (-1800 2200)(-2000 2200);
WIRE 16 -1 (-1800 2300)(-2000 2300);
WIRE 16 -1 (-1800 2250)(-2000 2250);
WIRE 16 -1 (-1800 2500)(-2000 2500);
WIRE 16 -1 (-1800 2400)(-2000 2400);
WIRE 16 -1 (-1800 2450)(-2000 2450);
WIRE 16 -1 (-1800 2550)(-2000 2550);
WIRE 16 -1 (-1800 2350)(-2000 2350);
WIRE 16 -1 (-1800 2600)(-2000 2600);
WIRE 16 -1 (-1800 2650)(-2000 2650);
WIRE 16 -1 (-1800 2700)(-2000 2700);
WIRE 16 -1 (-1800 2750)(-2000 2750);
WIRE 16 -1 (-1800 2800)(-2000 2800);
WIRE 16 -1 (-1800 3050)(-2000 3050);
WIRE 16 -1 (-1800 2850)(-2000 2850);
WIRE 16 -1 (-1800 2900)(-2000 2900);
WIRE 16 -1 (-1800 2950)(-2000 2950);
WIRE 16 -1 (-1800 3000)(-2000 3000);
WIRE 16 -1 (-1800 3100)(-2000 3100);
WIRE 16 -1 (-1800 3250)(-2000 3250);
WIRE 16 -1 (-1800 3300)(-2000 3300);
WIRE 16 -1 (-1800 3150)(-2000 3150);
WIRE 16 -1 (-1800 3200)(-2000 3200);
WIRE 16 -1 (-1800 3550)(-2000 3550);
WIRE 16 -1 (-1800 3500)(-2000 3500);
WIRE 16 -1 (-1800 3350)(-2000 3350);
WIRE 16 -1 (-1800 3400)(-2000 3400);
WIRE 16 -1 (-1800 3450)(-2000 3450);
WIRE 16 -1 (-1800 3650)(-2000 3650);
WIRE 16 -1 (-1800 3600)(-2000 3600);
WIRE 16 -1 (-1800 3700)(-2000 3700);
WIRE 16 -1 (-1800 3750)(-2000 3750);
WIRE 16 -1 (-1800 3800)(-2000 3800);
WIRE 16 -1 (-1800 3850)(-2000 3850);
WIRE 16 -1 (-1800 3900)(-2000 3900);
WIRE 16 -1 (-1800 3950)(-2000 3950);
WIRE 16 -1 (-1800 4000)(-2000 4000);
WIRE 16 -1 (-1800 4050)(-2000 4050);
WIRE 16 -1 (-3000 4850)(-3200 4850);
WIRE 16 -1 (-3000 4800)(-3200 4800);
WIRE 16 -1 (-3000 4750)(-3200 4750);
WIRE 16 -1 (-3000 4600)(-3200 4600);
WIRE 16 -1 (-3000 4550)(-3200 4550);
WIRE 16 -1 (-3000 4150)(-3200 4150);
WIRE 16 -1 (-3000 4500)(-3200 4500);
WIRE 16 -1 (-3000 4450)(-3200 4450);
WIRE 16 -1 (-3000 4400)(-3200 4400);
WIRE 16 -1 (-3000 4350)(-3200 4350);
WIRE 16 -1 (-3000 4300)(-3200 4300);
WIRE 16 -1 (-3000 4250)(-3200 4250);
WIRE 16 -1 (-3000 4200)(-3200 4200);
WIRE 16 -1 (-3000 4900)(-3200 4900);
WIRE 16 -1 (-3000 4700)(-3200 4700);
WIRE 16 -1 (-3000 4650)(-3200 4650);
WIRE 16 -1 (-3000 4100)(-3200 4100);
WIRE 16 -1 (-1800 4100)(-2000 4100);
WIRE 16 -1 (-1800 4150)(-2000 4150);
WIRE 16 -1 (-1800 4200)(-2000 4200);
WIRE 16 -1 (-1800 4250)(-2000 4250);
WIRE 16 -1 (-1800 4300)(-2000 4300);
WIRE 16 -1 (-1800 4350)(-2000 4350);
WIRE 16 -1 (-1800 4400)(-2000 4400);
WIRE 16 -1 (-1800 4450)(-2000 4450);
WIRE 16 -1 (-1800 4600)(-2000 4600);
WIRE 16 -1 (-1800 4500)(-2000 4500);
WIRE 16 -1 (-1800 4550)(-2000 4550);
WIRE 16 -1 (-1800 4850)(-2000 4850);
WIRE 16 -1 (-1800 4800)(-2000 4800);
WIRE 16 -1 (-1800 4650)(-2000 4650);
WIRE 16 -1 (-1800 4700)(-2000 4700);
WIRE 16 -1 (-1800 4750)(-2000 4750);
WIRE 16 -1 (-1800 4900)(-2000 4900);
WIRE 16 -1 (650 4050)(450 4050);
WIRE 16 -1 (850 4000)(450 4000);
WIRE 16 -1 (650 3950)(450 3950);
WIRE 16 -1 (850 3900)(450 3900);
WIRE 16 -1 (650 3850)(450 3850);
WIRE 16 -1 (850 3800)(450 3800);
WIRE 16 -1 (650 3750)(450 3750);
WIRE 16 -1 (850 3700)(450 3700);
WIRE 16 -1 (650 3650)(450 3650);
WIRE 16 -1 (850 3600)(450 3600);
WIRE 16 -1 (650 3550)(450 3550);
WIRE 16 -1 (850 3500)(450 3500);
WIRE 16 -1 (650 3450)(450 3450);
WIRE 16 -1 (850 3400)(450 3400);
WIRE 16 -1 (650 4350)(450 4350);
WIRE 16 -1 (850 4300)(450 4300);
WIRE 16 -1 (650 4250)(450 4250);
WIRE 16 -1 (850 4200)(450 4200);
WIRE 16 -1 (650 4150)(450 4150);
WIRE 16 -1 (850 4100)(450 4100);
WIRE 16 -1 (850 5100)(450 5100);
WIRE 16 -1 (650 5050)(450 5050);
WIRE 16 -1 (850 5000)(450 5000);
WIRE 16 -1 (650 4950)(450 4950);
WIRE 16 -1 (850 4900)(450 4900);
WIRE 16 -1 (650 4850)(450 4850);
WIRE 16 -1 (850 4800)(450 4800);
WIRE 16 -1 (650 4750)(450 4750);
WIRE 16 -1 (850 4700)(450 4700);
WIRE 16 -1 (650 4650)(450 4650);
WIRE 16 -1 (850 4600)(450 4600);
WIRE 16 -1 (650 4550)(450 4550);
WIRE 16 -1 (850 4500)(450 4500);
WIRE 16 -1 (650 4450)(450 4450);
WIRE 16 -1 (850 4400)(450 4400);
WIRE 16 -1 (650 5150)(450 5150);
DOT 1 (-3200 2100);
DOT 1 (-1100 2300);
DOT 1 (-1100 2250);
DOT 1 (-1100 2600);
DOT 1 (-3200 2000);
DOT 1 (-1100 2050);
DOT 1 (2500 1550);
DOT 1 (1100 1850);
DOT 1 (1100 1300);
DOT 1 (1100 1350);
DOT 1 (1100 1400);
DOT 1 (1100 1450);
DOT 1 (1100 1550);
DOT 1 (1100 1600);
DOT 1 (1100 1650);
DOT 1 (1100 1800);
DOT 1 (1100 1900);
DOT 1 (1100 1950);
DOT 1 (1100 2000);
DOT 1 (1100 2050);
DOT 1 (1100 2100);
DOT 1 (1100 2150);
DOT 1 (1100 2200);
DOT 1 (1100 2250);
DOT 1 (1100 2300);
DOT 1 (1100 2350);
DOT 1 (1100 2400);
DOT 1 (1100 2450);
DOT 1 (1100 2500);
DOT 1 (1100 2550);
DOT 1 (1100 2600);
DOT 1 (1100 2700);
DOT 1 (1100 2750);
DOT 1 (1100 2800);
DOT 1 (1100 2850);
DOT 1 (1100 2900);
DOT 1 (1100 2950);
DOT 1 (1100 3000);
DOT 1 (1100 3050);
DOT 1 (1100 3100);
DOT 1 (1100 3150);
DOT 1 (1100 3200);
DOT 1 (1100 3250);
DOT 1 (1100 3300);
DOT 1 (1100 3350);
DOT 1 (1100 3400);
DOT 1 (1100 3450);
DOT 1 (1100 3500);
DOT 1 (1100 3550);
DOT 1 (2500 1300);
DOT 1 (2500 1350);
DOT 1 (2500 1400);
DOT 1 (2500 1500);
DOT 1 (2500 1450);
DOT 1 (2500 1600);
DOT 1 (2500 1650);
DOT 1 (2500 1750);
DOT 1 (2500 1700);
DOT 1 (2500 1800);
DOT 1 (2500 1850);
DOT 1 (2500 1900);
DOT 1 (2500 2000);
DOT 1 (2500 1950);
DOT 1 (2500 2050);
DOT 1 (2500 2100);
DOT 1 (2500 2150);
DOT 1 (2500 2200);
DOT 1 (2500 2250);
DOT 1 (2500 2300);
DOT 1 (2500 2400);
DOT 1 (2500 2350);
DOT 1 (2500 2450);
DOT 1 (2500 2500);
DOT 1 (2500 2550);
DOT 1 (2500 2600);
DOT 1 (2500 2650);
DOT 1 (2500 2700);
DOT 1 (2500 2750);
DOT 1 (2500 2800);
DOT 1 (2500 2900);
DOT 1 (2500 2850);
DOT 1 (2500 2950);
DOT 1 (2500 3000);
DOT 1 (2500 3050);
DOT 1 (2500 3100);
DOT 1 (2500 3200);
DOT 1 (2500 3150);
DOT 1 (2500 3300);
DOT 1 (2500 3250);
DOT 1 (2500 3350);
DOT 1 (2500 3400);
DOT 1 (2500 3450);
DOT 1 (2500 3550);
DOT 1 (2500 3500);
DOT 1 (-1100 2900);
DOT 1 (-1100 2800);
DOT 1 (-1100 2850);
DOT 1 (-1100 2350);
DOT 1 (-1100 2400);
DOT 1 (-1100 2450);
DOT 1 (-1100 2200);
DOT 1 (-1100 2150);
DOT 1 (-1100 2100);
DOT 1 (-1100 1850);
DOT 1 (-1100 1900);
DOT 1 (-1100 1800);
DOT 1 (-1100 1750);
DOT 1 (-1100 1700);
DOT 1 (-1100 1650);
DOT 1 (-1100 1600);
DOT 1 (-1100 1450);
DOT 1 (-1100 1550);
DOT 1 (-1100 1500);
DOT 1 (-1100 1350);
DOT 1 (-1100 1400);
DOT 1 (-1100 1300);
DOT 1 (-1100 1250);
DOT 1 (-1100 2750);
DOT 1 (-1100 2000);
DOT 1 (300 2900);
DOT 1 (-1100 1950);
DOT 1 (1100 1500);
DOT 1 (1100 1700);
DOT 1 (1100 1750);
DOT 1 (1100 2650);
DOT 1 (-4650 1750);
FORCENOTE
PLACE CAP NEAR DIMM CONNECTOR
(-5288 1202) 0;
DISPLAY LEFT (-5288 1202);
DISPLAY 1.595745 (-5288 1202);
PAINT PURPLE (-5288 1202);
FORCENOTE
SMBUS ADDR: 0XA8
(-4225 1009) 0;
DISPLAY LEFT (-4225 1009);
DISPLAY 1.957447 (-4225 1009);
PAINT PURPLE (-4225 1009);
QUIT
